FILE_TYPE = MACRO_DRAWING;
SET COLOR_WIRE YELLOW;
SET COLOR_PROP MONO;
SET COLOR_DOT WHITE;
SET COLOR_ARC YELLOW;
SET COLOR_BODY GREEN;
SET COLOR_NOTE MONO;
SET PROP_DISPLAY VALUE;
SET PAGE_NUMBER P37;
FORCEADD PVCCIN_CPU0..1
(-7125 4350);
FORCEPROP 3 LASTPIN (-7125 4300) SIG_NAME PVCCIN_CPU0\g
J 0
(-7115 4310);
DISPLAY 0.659574 (-7115 4310);
PAINT MONO (-7115 4310);
DISPLAY INVISIBLE (-7115 4310);
FORCEPROP 1 LAST BODY_TYPE PLUMBING
J 0
(-7170 4307);
DISPLAY 0.340426 (-7170 4307);
PAINT GREEN (-7170 4307);
DISPLAY INVISIBLE (-7170 4307);
FORCEPROP 1 LAST VOLTAGE 2.0V
J 0
(-7170 4307);
DISPLAY 0.340426 (-7170 4307);
PAINT SKYBLUE (-7170 4307);
DISPLAY INVISIBLE (-7170 4307);
FORCEPROP 2 LAST CDS_LIB mstr_symbols
J 0
(-7125 4350);
PAINT ORANGE (-7125 4350);
DISPLAY INVISIBLE (-7125 4350);
FORCEPROP 1 LAST PATH I295
J 0
(-7075 4375);
DISPLAY 0.872340 (-7075 4375);
PAINT AQUA (-7075 4375);
DISPLAY INVISIBLE (-7075 4375);
FORCEPROP 1 LAST HDL_POWER PVCCIN_CPU0
J 1
(-7125 4400);
DISPLAY 0.872340 (-7125 4400);
PAINT GREEN (-7125 4400);
DISPLAY INVISIBLE (-7125 4400);
FORCEADD PVCCIN_CPU0..1
(-5250 4275);
FORCEPROP 3 LASTPIN (-5250 4225) SIG_NAME PVCCIN_CPU0\g
J 0
(-5240 4235);
DISPLAY 0.659574 (-5240 4235);
PAINT MONO (-5240 4235);
DISPLAY INVISIBLE (-5240 4235);
FORCEPROP 1 LAST VOLTAGE 2.0V
J 0
(-5295 4232);
DISPLAY 0.340426 (-5295 4232);
PAINT SKYBLUE (-5295 4232);
DISPLAY INVISIBLE (-5295 4232);
FORCEPROP 2 LAST CDS_LIB mstr_symbols
J 0
(-5250 4275);
PAINT ORANGE (-5250 4275);
DISPLAY INVISIBLE (-5250 4275);
FORCEPROP 1 LAST BODY_TYPE PLUMBING
J 0
(-5295 4232);
DISPLAY 0.340426 (-5295 4232);
PAINT GREEN (-5295 4232);
DISPLAY INVISIBLE (-5295 4232);
FORCEPROP 1 LAST PATH I296
J 0
(-5200 4300);
DISPLAY 0.872340 (-5200 4300);
PAINT AQUA (-5200 4300);
DISPLAY INVISIBLE (-5200 4300);
FORCEPROP 1 LAST HDL_POWER PVCCIN_CPU0
J 1
(-5250 4325);
DISPLAY 0.872340 (-5250 4325);
PAINT GREEN (-5250 4325);
DISPLAY INVISIBLE (-5250 4325);
FORCEADD OFFPAGE..2
(-750 725);
FORCEPROP 2 LAST $XR0 204 
J 0
(-561 725);
DISPLAY 0.638298 (-561 725);
PAINT MONO (-561 725);
FORCEPROP 1 LAST COMMENT_BODY TRUE
J 0
(-795 630);
DISPLAY 1.170213 (-795 630);
PAINT GREEN (-795 630);
DISPLAY INVISIBLE (-795 630);
FORCEPROP 2 LAST CDS_LIB mstr_standard
J 0
(-750 725);
PAINT ORANGE (-750 725);
DISPLAY INVISIBLE (-750 725);
FORCEPROP 2 LAST PATH I298
J 0
(-575 800);
DISPLAY 1.021277 (-575 800);
PAINT ORANGE (-575 800);
DISPLAY INVISIBLE (-575 800);
FORCEPROP 1 LAST OFFPAGE TRUE
J 0
(-425 600);
DISPLAY 1.170213 (-425 600);
PAINT GREEN (-425 600);
DISPLAY INVISIBLE (-425 600);
FORCEADD OFFPAGE..2
(-750 775);
FORCEPROP 2 LAST $XR0 204 
J 0
(-561 775);
DISPLAY 0.638298 (-561 775);
PAINT MONO (-561 775);
FORCEPROP 1 LAST COMMENT_BODY TRUE
J 0
(-795 680);
DISPLAY 1.170213 (-795 680);
PAINT GREEN (-795 680);
DISPLAY INVISIBLE (-795 680);
FORCEPROP 2 LAST PATH I299
J 0
(-575 850);
DISPLAY 1.021277 (-575 850);
PAINT ORANGE (-575 850);
DISPLAY INVISIBLE (-575 850);
FORCEPROP 2 LAST CDS_LIB mstr_standard
J 0
(-750 775);
PAINT ORANGE (-750 775);
DISPLAY INVISIBLE (-750 775);
FORCEPROP 1 LAST OFFPAGE TRUE
J 0
(-425 650);
DISPLAY 1.170213 (-425 650);
PAINT GREEN (-425 650);
DISPLAY INVISIBLE (-425 650);
FORCEADD PVCCIN_CPU0..1
(-3375 4350);
FORCEPROP 3 LASTPIN (-3375 4300) SIG_NAME PVCCIN_CPU0\g
J 0
(-3365 4310);
DISPLAY 0.659574 (-3365 4310);
PAINT MONO (-3365 4310);
DISPLAY INVISIBLE (-3365 4310);
FORCEPROP 1 LAST VOLTAGE 2.0V
J 0
(-3420 4307);
DISPLAY 0.340426 (-3420 4307);
PAINT SKYBLUE (-3420 4307);
DISPLAY INVISIBLE (-3420 4307);
FORCEPROP 1 LAST BODY_TYPE PLUMBING
J 0
(-3420 4307);
DISPLAY 0.340426 (-3420 4307);
PAINT GREEN (-3420 4307);
DISPLAY INVISIBLE (-3420 4307);
FORCEPROP 2 LAST CDS_LIB mstr_symbols
J 0
(-3375 4350);
PAINT ORANGE (-3375 4350);
DISPLAY INVISIBLE (-3375 4350);
FORCEPROP 1 LAST HDL_POWER PVCCIN_CPU0
J 1
(-3375 4400);
DISPLAY 0.872340 (-3375 4400);
PAINT GREEN (-3375 4400);
DISPLAY INVISIBLE (-3375 4400);
FORCEPROP 1 LAST PATH I300
J 0
(-3325 4375);
DISPLAY 0.872340 (-3325 4375);
PAINT AQUA (-3325 4375);
DISPLAY INVISIBLE (-3325 4375);
FORCEADD PVCCIN_CPU0..1
(-1500 4325);
FORCEPROP 3 LASTPIN (-1500 4275) SIG_NAME PVCCIN_CPU0\g
J 0
(-1490 4285);
DISPLAY 0.659574 (-1490 4285);
PAINT MONO (-1490 4285);
DISPLAY INVISIBLE (-1490 4285);
FORCEPROP 1 LAST BODY_TYPE PLUMBING
J 0
(-1545 4282);
DISPLAY 0.340426 (-1545 4282);
PAINT GREEN (-1545 4282);
DISPLAY INVISIBLE (-1545 4282);
FORCEPROP 1 LAST VOLTAGE 2.0V
J 0
(-1545 4282);
DISPLAY 0.340426 (-1545 4282);
PAINT SKYBLUE (-1545 4282);
DISPLAY INVISIBLE (-1545 4282);
FORCEPROP 2 LAST CDS_LIB mstr_symbols
J 0
(-1500 4325);
PAINT ORANGE (-1500 4325);
DISPLAY INVISIBLE (-1500 4325);
FORCEPROP 1 LAST PATH I301
J 0
(-1450 4350);
DISPLAY 0.872340 (-1450 4350);
PAINT AQUA (-1450 4350);
DISPLAY INVISIBLE (-1450 4350);
FORCEPROP 1 LAST HDL_POWER PVCCIN_CPU0
J 1
(-1500 4375);
DISPLAY 0.872340 (-1500 4375);
PAINT GREEN (-1500 4375);
DISPLAY INVISIBLE (-1500 4375);
FORCEADD GND..1
(-375 525);
FORCEPROP 3 LASTPIN (-375 575) SIG_NAME GND\g
J 0
(-365 585);
DISPLAY 0.659574 (-365 585);
PAINT MONO (-365 585);
DISPLAY INVISIBLE (-365 585);
FORCEPROP 1 LAST BODY_TYPE PLUMBING
J 0
(-420 482);
DISPLAY 0.340426 (-420 482);
PAINT GREEN (-420 482);
DISPLAY INVISIBLE (-420 482);
FORCEPROP 1 LAST VOLTAGE 0.0V
J 0
(-420 482);
DISPLAY 0.340426 (-420 482);
PAINT SKYBLUE (-420 482);
DISPLAY INVISIBLE (-420 482);
FORCEPROP 1 LAST SIZE 1B
J 0
(-300 475);
DISPLAY 1.170213 (-300 475);
PAINT AQUA (-300 475);
DISPLAY INVISIBLE (-300 475);
FORCEPROP 1 LAST HDL_POWER GND
J 0
(-375 675);
DISPLAY 1.170213 (-375 675);
PAINT GREEN (-375 675);
DISPLAY INVISIBLE (-375 675);
FORCEPROP 1 LAST PATH I302
J 0
(-300 525);
DISPLAY 0.872340 (-300 525);
PAINT AQUA (-300 525);
DISPLAY INVISIBLE (-300 525);
FORCEPROP 2 LAST CDS_LIB mstr_symbols
J 0
(-375 525);
PAINT ORANGE (-375 525);
DISPLAY INVISIBLE (-375 525);
FORCEADD RES..2
(-375 750);
FORCEPROP 1 LASTPIN (-375 650) $PN 2
J 0
(-370 660);
DISPLAY 0.617021 (-370 660);
PAINT ORANGE (-370 660);
FORCEPROP 1 LASTPIN (-375 850) $PN 1
J 0
(-370 812);
DISPLAY 0.617021 (-370 812);
PAINT ORANGE (-370 812);
FORCEPROP 1 LAST WATTAGE 1/16W
J 0
(-335 725);
DISPLAY 0.617021 (-335 725);
PAINT SKYBLUE (-335 725);
FORCEPROP 1 LAST MATERIAL CHIP
J 0
(-335 675);
DISPLAY 0.617021 (-335 675);
PAINT SKYBLUE (-335 675);
FORCEPROP 1 LAST PACK_TYPE 0402
J 0
(-335 575);
DISPLAY 0.617021 (-335 575);
PAINT SKYBLUE (-335 575);
FORCEPROP 1 LAST TOLERANCE 0.1%
J 0
(-330 775);
DISPLAY 0.617021 (-330 775);
PAINT SKYBLUE (-330 775);
FORCEPROP 1 LAST VALUE 249
J 0
(-330 825);
DISPLAY 0.617021 (-330 825);
PAINT SKYBLUE (-330 825);
FORCEPROP 1 LAST PART_NUMBER G85996-031
J 0
(-335 625);
DISPLAY 0.617021 (-335 625);
PAINT BLUE (-335 625);
FORCEPROP 1 LAST LOCATION R5D5
J 0
(-330 875);
DISPLAY 0.617021 (-330 875);
PAINT AQUA (-330 875);
FORCEPROP 2 LAST CDS_LIB mstr_discrete
J 0
(-375 750);
PAINT ORANGE (-375 750);
DISPLAY INVISIBLE (-375 750);
FORCEPROP 2 LAST CDS_LOCATION R5D5
J 0
(-330 875);
DISPLAY 0.617021 (-330 875);
PAINT AQUA (-330 875);
DISPLAY INVISIBLE (-330 875);
FORCEPROP 2 LAST ROOM CPU0
J 0
(-325 925);
DISPLAY 1.021277 (-325 925);
PAINT ORANGE (-325 925);
DISPLAY INVISIBLE (-325 925);
FORCEPROP 1 LAST PATH I303
J 0
(-325 925);
DISPLAY 0.978723 (-325 925);
PAINT WHITE (-325 925);
DISPLAY INVISIBLE (-325 925);
FORCEPROP 2 LAST SEC 1
J 0
(-325 975);
DISPLAY 0.680851 (-325 975);
PAINT MONO (-325 975);
DISPLAY INVISIBLE (-325 975);
FORCEPROP 2 LAST SEC_TYPE 0402
J 0
(-325 975);
DISPLAY 1.021277 (-325 975);
PAINT ORANGE (-325 975);
DISPLAY INVISIBLE (-325 975);
FORCEPROP 2 LAST BOM_COST PROC_SOCKET
J 0
(-325 975);
DISPLAY 1.021277 (-325 975);
PAINT ORANGE (-325 975);
DISPLAY INVISIBLE (-325 975);
FORCEADD PVCCIN_CPU0..1
(-775 1625);
FORCEPROP 3 LASTPIN (-775 1575) SIG_NAME PVCCIN_CPU0\g
J 0
(-765 1585);
DISPLAY 0.659574 (-765 1585);
PAINT MONO (-765 1585);
DISPLAY INVISIBLE (-765 1585);
FORCEPROP 1 LAST HDL_POWER PVCCIN_CPU0
J 1
(-775 1675);
DISPLAY 0.872340 (-775 1675);
PAINT GREEN (-775 1675);
DISPLAY INVISIBLE (-775 1675);
FORCEPROP 1 LAST PATH I305
J 0
(-725 1650);
DISPLAY 0.872340 (-725 1650);
PAINT AQUA (-725 1650);
DISPLAY INVISIBLE (-725 1650);
FORCEPROP 1 LAST BODY_TYPE PLUMBING
J 0
(-820 1582);
DISPLAY 0.340426 (-820 1582);
PAINT GREEN (-820 1582);
DISPLAY INVISIBLE (-820 1582);
FORCEPROP 2 LAST CDS_LIB mstr_symbols
J 0
(-775 1625);
PAINT ORANGE (-775 1625);
DISPLAY INVISIBLE (-775 1625);
FORCEPROP 1 LAST VOLTAGE 2.0V
J 0
(-820 1582);
DISPLAY 0.340426 (-820 1582);
PAINT SKYBLUE (-820 1582);
DISPLAY INVISIBLE (-820 1582);
FORCEADD RES..2
(-775 1350);
FORCEPROP 1 LAST WATTAGE 1/10W
J 0
(-735 1325);
DISPLAY 0.617021 (-735 1325);
PAINT SKYBLUE (-735 1325);
FORCEPROP 1 LAST MATERIAL CHIP
J 0
(-735 1275);
DISPLAY 0.617021 (-735 1275);
PAINT SKYBLUE (-735 1275);
FORCEPROP 1 LAST PART_NUMBER G22026-050
J 0
(-735 1225);
DISPLAY 0.617021 (-735 1225);
PAINT BLUE (-735 1225);
FORCEPROP 1 LASTPIN (-775 1250) $PN 2
J 0
(-770 1260);
DISPLAY 0.617021 (-770 1260);
PAINT ORANGE (-770 1260);
FORCEPROP 1 LASTPIN (-775 1450) $PN 1
J 0
(-770 1412);
DISPLAY 0.617021 (-770 1412);
PAINT ORANGE (-770 1412);
FORCEPROP 1 LAST LOCATION R5P1
J 0
(-725 1475);
DISPLAY 0.617021 (-725 1475);
PAINT AQUA (-725 1475);
FORCEPROP 1 LAST VALUE 100.0K
J 0
(-730 1425);
DISPLAY 0.617021 (-730 1425);
PAINT SKYBLUE (-730 1425);
FORCEPROP 1 LAST PACK_TYPE 0603
J 0
(-735 1175);
DISPLAY 0.617021 (-735 1175);
PAINT SKYBLUE (-735 1175);
FORCEPROP 1 LAST TOLERANCE 1%
J 0
(-730 1375);
DISPLAY 0.617021 (-730 1375);
PAINT SKYBLUE (-730 1375);
FORCEPROP 2 LAST CDS_LIB mstr_discrete
J 0
(-775 1350);
PAINT ORANGE (-775 1350);
DISPLAY INVISIBLE (-775 1350);
FORCEPROP 2 LAST CDS_LOCATION R5P1
J 0
(-725 1475);
DISPLAY 0.617021 (-725 1475);
PAINT AQUA (-725 1475);
DISPLAY INVISIBLE (-725 1475);
FORCEPROP 2 LAST ROOM CPU0
J 0
(-700 1450);
DISPLAY 1.021277 (-700 1450);
PAINT ORANGE (-700 1450);
DISPLAY INVISIBLE (-700 1450);
FORCEPROP 1 LAST PATH I309
J 0
(-725 1525);
DISPLAY 0.978723 (-725 1525);
PAINT WHITE (-725 1525);
DISPLAY INVISIBLE (-725 1525);
FORCEPROP 2 LAST BOM_COST PROC_SOCKET
J 0
(-700 1500);
DISPLAY 1.021277 (-700 1500);
PAINT ORANGE (-700 1500);
DISPLAY INVISIBLE (-700 1500);
FORCEPROP 2 LAST SEC 1
J 0
(-725 1575);
DISPLAY 0.680851 (-725 1575);
PAINT MONO (-725 1575);
DISPLAY INVISIBLE (-725 1575);
FORCEPROP 2 LAST SEC_TYPE 0603
J 0
(-725 1575);
DISPLAY 1.021277 (-725 1575);
PAINT ORANGE (-725 1575);
DISPLAY INVISIBLE (-725 1575);
FORCEADD SKX_EXT_B..18
(-6200 2475);
FORCEPROP 2 LASTPIN (-6900 775) $PN BF85
J 2
(-6910 785);
DISPLAY 0.617021 (-6910 785);
PAINT ORANGE (-6910 785);
FORCEPROP 2 LASTPIN (-6900 825) $PN BF83
J 2
(-6910 835);
DISPLAY 0.617021 (-6910 835);
PAINT ORANGE (-6910 835);
FORCEPROP 2 LASTPIN (-6900 875) $PN BF81
J 2
(-6910 885);
DISPLAY 0.617021 (-6910 885);
PAINT ORANGE (-6910 885);
FORCEPROP 2 LASTPIN (-6900 925) $PN BF79
J 2
(-6910 935);
DISPLAY 0.617021 (-6910 935);
PAINT ORANGE (-6910 935);
FORCEPROP 2 LASTPIN (-6900 975) $PN BF77
J 2
(-6910 985);
DISPLAY 0.617021 (-6910 985);
PAINT ORANGE (-6910 985);
FORCEPROP 1 LAST PART_NUMBER TBD
J 0
(-6850 575);
DISPLAY 0.617021 (-6850 575);
PAINT BLUE (-6850 575);
FORCEPROP 2 LASTPIN (-6900 1025) $PN BF75
J 2
(-6910 1035);
DISPLAY 0.617021 (-6910 1035);
PAINT ORANGE (-6910 1035);
FORCEPROP 2 LASTPIN (-6900 1075) $PN BF73
J 2
(-6910 1085);
DISPLAY 0.617021 (-6910 1085);
PAINT ORANGE (-6910 1085);
FORCEPROP 2 LASTPIN (-6900 1125) $PN BF61
J 2
(-6910 1135);
DISPLAY 0.617021 (-6910 1135);
PAINT ORANGE (-6910 1135);
FORCEPROP 2 LASTPIN (-6900 1175) $PN BE84
J 2
(-6910 1185);
DISPLAY 0.617021 (-6910 1185);
PAINT ORANGE (-6910 1185);
FORCEPROP 2 LASTPIN (-6900 1225) $PN BE82
J 2
(-6910 1235);
DISPLAY 0.617021 (-6910 1235);
PAINT ORANGE (-6910 1235);
FORCEPROP 2 LASTPIN (-6900 1275) $PN BE80
J 2
(-6910 1285);
DISPLAY 0.617021 (-6910 1285);
PAINT ORANGE (-6910 1285);
FORCEPROP 2 LASTPIN (-6900 1325) $PN BE78
J 2
(-6910 1335);
DISPLAY 0.617021 (-6910 1335);
PAINT ORANGE (-6910 1335);
FORCEPROP 2 LASTPIN (-6900 1375) $PN BE76
J 2
(-6910 1385);
DISPLAY 0.617021 (-6910 1385);
PAINT ORANGE (-6910 1385);
FORCEPROP 2 LASTPIN (-6900 1425) $PN BE74
J 2
(-6910 1435);
DISPLAY 0.617021 (-6910 1435);
PAINT ORANGE (-6910 1435);
FORCEPROP 2 LASTPIN (-6900 1475) $PN BE72
J 2
(-6910 1485);
DISPLAY 0.617021 (-6910 1485);
PAINT ORANGE (-6910 1485);
FORCEPROP 2 LASTPIN (-6900 1525) $PN BE62
J 2
(-6910 1535);
DISPLAY 0.617021 (-6910 1535);
PAINT ORANGE (-6910 1535);
FORCEPROP 2 LASTPIN (-6900 1575) $PN BE60
J 2
(-6910 1585);
DISPLAY 0.617021 (-6910 1585);
PAINT ORANGE (-6910 1585);
FORCEPROP 2 LASTPIN (-6900 1625) $PN BD85
J 2
(-6910 1635);
DISPLAY 0.617021 (-6910 1635);
PAINT ORANGE (-6910 1635);
FORCEPROP 2 LASTPIN (-6900 1675) $PN BD83
J 2
(-6910 1685);
DISPLAY 0.617021 (-6910 1685);
PAINT ORANGE (-6910 1685);
FORCEPROP 2 LASTPIN (-6900 1725) $PN BD81
J 2
(-6910 1735);
DISPLAY 0.617021 (-6910 1735);
PAINT ORANGE (-6910 1735);
FORCEPROP 2 LASTPIN (-6900 1775) $PN BD79
J 2
(-6910 1785);
DISPLAY 0.617021 (-6910 1785);
PAINT ORANGE (-6910 1785);
FORCEPROP 2 LASTPIN (-6900 1825) $PN BD77
J 2
(-6910 1835);
DISPLAY 0.617021 (-6910 1835);
PAINT ORANGE (-6910 1835);
FORCEPROP 2 LASTPIN (-6900 1875) $PN BD75
J 2
(-6910 1885);
DISPLAY 0.617021 (-6910 1885);
PAINT ORANGE (-6910 1885);
FORCEPROP 2 LASTPIN (-6900 1925) $PN BD73
J 2
(-6910 1935);
DISPLAY 0.617021 (-6910 1935);
PAINT ORANGE (-6910 1935);
FORCEPROP 2 LASTPIN (-6900 1975) $PN BD61
J 2
(-6910 1985);
DISPLAY 0.617021 (-6910 1985);
PAINT ORANGE (-6910 1985);
FORCEPROP 2 LASTPIN (-6900 2025) $PN BC84
J 2
(-6910 2035);
DISPLAY 0.617021 (-6910 2035);
PAINT ORANGE (-6910 2035);
FORCEPROP 2 LASTPIN (-6900 2075) $PN BC62
J 2
(-6910 2085);
DISPLAY 0.617021 (-6910 2085);
PAINT ORANGE (-6910 2085);
FORCEPROP 2 LASTPIN (-6900 2125) $PN BC60
J 2
(-6910 2135);
DISPLAY 0.617021 (-6910 2135);
PAINT ORANGE (-6910 2135);
FORCEPROP 2 LASTPIN (-6900 2175) $PN BB85
J 2
(-6910 2185);
DISPLAY 0.617021 (-6910 2185);
PAINT ORANGE (-6910 2185);
FORCEPROP 2 LASTPIN (-6900 2225) $PN BB61
J 2
(-6910 2235);
DISPLAY 0.617021 (-6910 2235);
PAINT ORANGE (-6910 2235);
FORCEPROP 2 LASTPIN (-6900 2275) $PN BA60
J 2
(-6910 2285);
DISPLAY 0.617021 (-6910 2285);
PAINT ORANGE (-6910 2285);
FORCEPROP 2 LASTPIN (-6900 2325) $PN AY61
J 2
(-6910 2335);
DISPLAY 0.617021 (-6910 2335);
PAINT ORANGE (-6910 2335);
FORCEPROP 2 LASTPIN (-6900 2375) $PN AW60
J 2
(-6910 2385);
DISPLAY 0.617021 (-6910 2385);
PAINT ORANGE (-6910 2385);
FORCEPROP 2 LASTPIN (-6900 2425) $PN AV61
J 2
(-6910 2435);
DISPLAY 0.617021 (-6910 2435);
PAINT ORANGE (-6910 2435);
FORCEPROP 2 LASTPIN (-6900 2475) $PN AV59
J 2
(-6910 2485);
DISPLAY 0.617021 (-6910 2485);
PAINT ORANGE (-6910 2485);
FORCEPROP 2 LASTPIN (-6900 2525) $PN AU60
J 2
(-6910 2535);
DISPLAY 0.617021 (-6910 2535);
PAINT ORANGE (-6910 2535);
FORCEPROP 2 LASTPIN (-6900 2575) $PN AU58
J 2
(-6910 2585);
DISPLAY 0.617021 (-6910 2585);
PAINT ORANGE (-6910 2585);
FORCEPROP 2 LASTPIN (-6900 2625) $PN AT59
J 2
(-6910 2635);
DISPLAY 0.617021 (-6910 2635);
PAINT ORANGE (-6910 2635);
FORCEPROP 2 LASTPIN (-6900 2675) $PN AT57
J 2
(-6910 2685);
DISPLAY 0.617021 (-6910 2685);
PAINT ORANGE (-6910 2685);
FORCEPROP 2 LASTPIN (-6900 2725) $PN AR58
J 2
(-6910 2735);
DISPLAY 0.617021 (-6910 2735);
PAINT ORANGE (-6910 2735);
FORCEPROP 2 LASTPIN (-6900 2775) $PN AR56
J 2
(-6910 2785);
DISPLAY 0.617021 (-6910 2785);
PAINT ORANGE (-6910 2785);
FORCEPROP 2 LASTPIN (-6900 2825) $PN AP57
J 2
(-6910 2835);
DISPLAY 0.617021 (-6910 2835);
PAINT ORANGE (-6910 2835);
FORCEPROP 2 LASTPIN (-6900 2875) $PN AP55
J 2
(-6910 2885);
DISPLAY 0.617021 (-6910 2885);
PAINT ORANGE (-6910 2885);
FORCEPROP 2 LASTPIN (-6900 2925) $PN AN56
J 2
(-6910 2935);
DISPLAY 0.617021 (-6910 2935);
PAINT ORANGE (-6910 2935);
FORCEPROP 2 LASTPIN (-6900 2975) $PN AN54
J 2
(-6910 2985);
DISPLAY 0.617021 (-6910 2985);
PAINT ORANGE (-6910 2985);
FORCEPROP 2 LASTPIN (-6900 3025) $PN AN32
J 2
(-6910 3035);
DISPLAY 0.617021 (-6910 3035);
PAINT ORANGE (-6910 3035);
FORCEPROP 2 LASTPIN (-6900 3075) $PN AM55
J 2
(-6910 3085);
DISPLAY 0.617021 (-6910 3085);
PAINT ORANGE (-6910 3085);
FORCEPROP 2 LASTPIN (-6900 3125) $PN AM53
J 2
(-6910 3135);
DISPLAY 0.617021 (-6910 3135);
PAINT ORANGE (-6910 3135);
FORCEPROP 2 LASTPIN (-6900 3175) $PN AM33
J 2
(-6910 3185);
DISPLAY 0.617021 (-6910 3185);
PAINT ORANGE (-6910 3185);
FORCEPROP 2 LASTPIN (-6900 3225) $PN AL54
J 2
(-6910 3235);
DISPLAY 0.617021 (-6910 3235);
PAINT ORANGE (-6910 3235);
FORCEPROP 2 LASTPIN (-6900 3275) $PN AL52
J 2
(-6910 3285);
DISPLAY 0.617021 (-6910 3285);
PAINT ORANGE (-6910 3285);
FORCEPROP 2 LASTPIN (-6900 3325) $PN AL50
J 2
(-6910 3335);
DISPLAY 0.617021 (-6910 3335);
PAINT ORANGE (-6910 3335);
FORCEPROP 2 LASTPIN (-6900 3375) $PN AL48
J 2
(-6910 3385);
DISPLAY 0.617021 (-6910 3385);
PAINT ORANGE (-6910 3385);
FORCEPROP 2 LASTPIN (-6900 3425) $PN AL46
J 2
(-6910 3435);
DISPLAY 0.617021 (-6910 3435);
PAINT ORANGE (-6910 3435);
FORCEPROP 2 LASTPIN (-6900 3475) $PN AL34
J 2
(-6910 3485);
DISPLAY 0.617021 (-6910 3485);
PAINT ORANGE (-6910 3485);
FORCEPROP 2 LASTPIN (-6900 3525) $PN AK53
J 2
(-6910 3535);
DISPLAY 0.617021 (-6910 3535);
PAINT ORANGE (-6910 3535);
FORCEPROP 2 LASTPIN (-6900 3575) $PN AK51
J 2
(-6910 3585);
DISPLAY 0.617021 (-6910 3585);
PAINT ORANGE (-6910 3585);
FORCEPROP 2 LASTPIN (-6900 3625) $PN AK49
J 2
(-6910 3635);
DISPLAY 0.617021 (-6910 3635);
PAINT ORANGE (-6910 3635);
FORCEPROP 2 LASTPIN (-6900 3675) $PN AK47
J 2
(-6910 3685);
DISPLAY 0.617021 (-6910 3685);
PAINT ORANGE (-6910 3685);
FORCEPROP 2 LASTPIN (-6900 3725) $PN AK45
J 2
(-6910 3735);
DISPLAY 0.617021 (-6910 3735);
PAINT ORANGE (-6910 3735);
FORCEPROP 2 LASTPIN (-6900 3775) $PN AK35
J 2
(-6910 3785);
DISPLAY 0.617021 (-6910 3785);
PAINT ORANGE (-6910 3785);
FORCEPROP 2 LASTPIN (-6900 3825) $PN AJ36
J 2
(-6910 3835);
DISPLAY 0.617021 (-6910 3835);
PAINT ORANGE (-6910 3835);
FORCEPROP 2 LASTPIN (-6900 3875) $PN AH41
J 2
(-6910 3885);
DISPLAY 0.617021 (-6910 3885);
PAINT ORANGE (-6910 3885);
FORCEPROP 2 LASTPIN (-6900 3925) $PN AH39
J 2
(-6910 3935);
DISPLAY 0.617021 (-6910 3935);
PAINT ORANGE (-6910 3935);
FORCEPROP 2 LASTPIN (-6900 3975) $PN AH37
J 2
(-6910 3985);
DISPLAY 0.617021 (-6910 3985);
PAINT ORANGE (-6910 3985);
FORCEPROP 2 LASTPIN (-6900 4025) $PN AG42
J 2
(-6910 4035);
DISPLAY 0.617021 (-6910 4035);
PAINT ORANGE (-6910 4035);
FORCEPROP 2 LASTPIN (-5500 775) $PN BN78
J 0
(-5490 785);
DISPLAY 0.617021 (-5490 785);
PAINT ORANGE (-5490 785);
FORCEPROP 2 LASTPIN (-5500 825) $PN BN76
J 0
(-5490 835);
DISPLAY 0.617021 (-5490 835);
PAINT ORANGE (-5490 835);
FORCEPROP 2 LASTPIN (-5500 875) $PN BN74
J 0
(-5490 885);
DISPLAY 0.617021 (-5490 885);
PAINT ORANGE (-5490 885);
FORCEPROP 2 LASTPIN (-5500 925) $PN BN72
J 0
(-5490 935);
DISPLAY 0.617021 (-5490 935);
PAINT ORANGE (-5490 935);
FORCEPROP 2 LASTPIN (-5500 975) $PN BN70
J 0
(-5490 985);
DISPLAY 0.617021 (-5490 985);
PAINT ORANGE (-5490 985);
FORCEPROP 2 LASTPIN (-5500 1025) $PN BN68
J 0
(-5490 1035);
DISPLAY 0.617021 (-5490 1035);
PAINT ORANGE (-5490 1035);
FORCEPROP 2 LASTPIN (-5500 1075) $PN BN66
J 0
(-5490 1085);
DISPLAY 0.617021 (-5490 1085);
PAINT ORANGE (-5490 1085);
FORCEPROP 2 LASTPIN (-5500 1125) $PN BN64
J 0
(-5490 1135);
DISPLAY 0.617021 (-5490 1135);
PAINT ORANGE (-5490 1135);
FORCEPROP 2 LASTPIN (-5500 1175) $PN BN62
J 0
(-5490 1185);
DISPLAY 0.617021 (-5490 1185);
PAINT ORANGE (-5490 1185);
FORCEPROP 2 LASTPIN (-5500 1225) $PN BN60
J 0
(-5490 1235);
DISPLAY 0.617021 (-5490 1235);
PAINT ORANGE (-5490 1235);
FORCEPROP 2 LASTPIN (-5500 1275) $PN BM83
J 0
(-5490 1285);
DISPLAY 0.617021 (-5490 1285);
PAINT ORANGE (-5490 1285);
FORCEPROP 2 LASTPIN (-5500 1325) $PN BM81
J 0
(-5490 1335);
DISPLAY 0.617021 (-5490 1335);
PAINT ORANGE (-5490 1335);
FORCEPROP 2 LASTPIN (-5500 1375) $PN BM79
J 0
(-5490 1385);
DISPLAY 0.617021 (-5490 1385);
PAINT ORANGE (-5490 1385);
FORCEPROP 2 LASTPIN (-5500 1425) $PN BM77
J 0
(-5490 1435);
DISPLAY 0.617021 (-5490 1435);
PAINT ORANGE (-5490 1435);
FORCEPROP 2 LASTPIN (-5500 1475) $PN BM75
J 0
(-5490 1485);
DISPLAY 0.617021 (-5490 1485);
PAINT ORANGE (-5490 1485);
FORCEPROP 2 LASTPIN (-5500 1525) $PN BM73
J 0
(-5490 1535);
DISPLAY 0.617021 (-5490 1535);
PAINT ORANGE (-5490 1535);
FORCEPROP 2 LASTPIN (-5500 1575) $PN BM71
J 0
(-5490 1585);
DISPLAY 0.617021 (-5490 1585);
PAINT ORANGE (-5490 1585);
FORCEPROP 2 LASTPIN (-5500 1625) $PN BM69
J 0
(-5490 1635);
DISPLAY 0.617021 (-5490 1635);
PAINT ORANGE (-5490 1635);
FORCEPROP 2 LASTPIN (-5500 1675) $PN BM67
J 0
(-5490 1685);
DISPLAY 0.617021 (-5490 1685);
PAINT ORANGE (-5490 1685);
FORCEPROP 2 LASTPIN (-5500 1725) $PN BM65
J 0
(-5490 1735);
DISPLAY 0.617021 (-5490 1735);
PAINT ORANGE (-5490 1735);
FORCEPROP 2 LASTPIN (-5500 1775) $PN BM63
J 0
(-5490 1785);
DISPLAY 0.617021 (-5490 1785);
PAINT ORANGE (-5490 1785);
FORCEPROP 2 LASTPIN (-5500 1825) $PN BM61
J 0
(-5490 1835);
DISPLAY 0.617021 (-5490 1835);
PAINT ORANGE (-5490 1835);
FORCEPROP 2 LASTPIN (-5500 1875) $PN BL84
J 0
(-5490 1885);
DISPLAY 0.617021 (-5490 1885);
PAINT ORANGE (-5490 1885);
FORCEPROP 2 LASTPIN (-5500 1925) $PN BL62
J 0
(-5490 1935);
DISPLAY 0.617021 (-5490 1935);
PAINT ORANGE (-5490 1935);
FORCEPROP 2 LASTPIN (-5500 1975) $PN BL60
J 0
(-5490 1985);
DISPLAY 0.617021 (-5490 1985);
PAINT ORANGE (-5490 1985);
FORCEPROP 2 LASTPIN (-5500 2025) $PN BK83
J 0
(-5490 2035);
DISPLAY 0.617021 (-5490 2035);
PAINT ORANGE (-5490 2035);
FORCEPROP 2 LASTPIN (-5500 2075) $PN BK81
J 0
(-5490 2085);
DISPLAY 0.617021 (-5490 2085);
PAINT ORANGE (-5490 2085);
FORCEPROP 2 LASTPIN (-5500 2125) $PN BK79
J 0
(-5490 2135);
DISPLAY 0.617021 (-5490 2135);
PAINT ORANGE (-5490 2135);
FORCEPROP 2 LASTPIN (-5500 2175) $PN BK77
J 0
(-5490 2185);
DISPLAY 0.617021 (-5490 2185);
PAINT ORANGE (-5490 2185);
FORCEPROP 2 LASTPIN (-5500 2225) $PN BK75
J 0
(-5490 2235);
DISPLAY 0.617021 (-5490 2235);
PAINT ORANGE (-5490 2235);
FORCEPROP 2 LASTPIN (-5500 2275) $PN BK73
J 0
(-5490 2285);
DISPLAY 0.617021 (-5490 2285);
PAINT ORANGE (-5490 2285);
FORCEPROP 2 LASTPIN (-5500 2325) $PN BK71
J 0
(-5490 2335);
DISPLAY 0.617021 (-5490 2335);
PAINT ORANGE (-5490 2335);
FORCEPROP 2 LASTPIN (-5500 2375) $PN BK69
J 0
(-5490 2385);
DISPLAY 0.617021 (-5490 2385);
PAINT ORANGE (-5490 2385);
FORCEPROP 2 LASTPIN (-5500 2425) $PN BK67
J 0
(-5490 2435);
DISPLAY 0.617021 (-5490 2435);
PAINT ORANGE (-5490 2435);
FORCEPROP 2 LASTPIN (-5500 2475) $PN BK65
J 0
(-5490 2485);
DISPLAY 0.617021 (-5490 2485);
PAINT ORANGE (-5490 2485);
FORCEPROP 2 LASTPIN (-5500 2525) $PN BK63
J 0
(-5490 2535);
DISPLAY 0.617021 (-5490 2535);
PAINT ORANGE (-5490 2535);
FORCEPROP 2 LASTPIN (-5500 2575) $PN BK61
J 0
(-5490 2585);
DISPLAY 0.617021 (-5490 2585);
PAINT ORANGE (-5490 2585);
FORCEPROP 2 LASTPIN (-5500 2625) $PN BJ84
J 0
(-5490 2635);
DISPLAY 0.617021 (-5490 2635);
PAINT ORANGE (-5490 2635);
FORCEPROP 2 LASTPIN (-5500 2675) $PN BJ82
J 0
(-5490 2685);
DISPLAY 0.617021 (-5490 2685);
PAINT ORANGE (-5490 2685);
FORCEPROP 2 LASTPIN (-5500 2725) $PN BJ80
J 0
(-5490 2735);
DISPLAY 0.617021 (-5490 2735);
PAINT ORANGE (-5490 2735);
FORCEPROP 2 LASTPIN (-5500 2775) $PN BJ78
J 0
(-5490 2785);
DISPLAY 0.617021 (-5490 2785);
PAINT ORANGE (-5490 2785);
FORCEPROP 2 LASTPIN (-5500 2825) $PN BJ76
J 0
(-5490 2835);
DISPLAY 0.617021 (-5490 2835);
PAINT ORANGE (-5490 2835);
FORCEPROP 2 LASTPIN (-5500 2875) $PN BJ74
J 0
(-5490 2885);
DISPLAY 0.617021 (-5490 2885);
PAINT ORANGE (-5490 2885);
FORCEPROP 2 LASTPIN (-5500 2925) $PN BJ72
J 0
(-5490 2935);
DISPLAY 0.617021 (-5490 2935);
PAINT ORANGE (-5490 2935);
FORCEPROP 2 LASTPIN (-5500 2975) $PN BJ70
J 0
(-5490 2985);
DISPLAY 0.617021 (-5490 2985);
PAINT ORANGE (-5490 2985);
FORCEPROP 2 LASTPIN (-5500 3025) $PN BJ68
J 0
(-5490 3035);
DISPLAY 0.617021 (-5490 3035);
PAINT ORANGE (-5490 3035);
FORCEPROP 2 LASTPIN (-5500 3075) $PN BJ66
J 0
(-5490 3085);
DISPLAY 0.617021 (-5490 3085);
PAINT ORANGE (-5490 3085);
FORCEPROP 2 LASTPIN (-5500 3125) $PN BJ64
J 0
(-5490 3135);
DISPLAY 0.617021 (-5490 3135);
PAINT ORANGE (-5490 3135);
FORCEPROP 2 LASTPIN (-5500 3225) $PN BJ60
J 0
(-5490 3235);
DISPLAY 0.617021 (-5490 3235);
PAINT ORANGE (-5490 3235);
FORCEPROP 2 LASTPIN (-5500 3275) $PN BH83
J 0
(-5490 3285);
DISPLAY 0.617021 (-5490 3285);
PAINT ORANGE (-5490 3285);
FORCEPROP 2 LASTPIN (-5500 3325) $PN BH81
J 0
(-5490 3335);
DISPLAY 0.617021 (-5490 3335);
PAINT ORANGE (-5490 3335);
FORCEPROP 2 LASTPIN (-5500 3375) $PN BH79
J 0
(-5490 3385);
DISPLAY 0.617021 (-5490 3385);
PAINT ORANGE (-5490 3385);
FORCEPROP 2 LASTPIN (-5500 3425) $PN BH77
J 0
(-5490 3435);
DISPLAY 0.617021 (-5490 3435);
PAINT ORANGE (-5490 3435);
FORCEPROP 2 LASTPIN (-5500 3475) $PN BH75
J 0
(-5490 3485);
DISPLAY 0.617021 (-5490 3485);
PAINT ORANGE (-5490 3485);
FORCEPROP 2 LASTPIN (-5500 3525) $PN BH73
J 0
(-5490 3535);
DISPLAY 0.617021 (-5490 3535);
PAINT ORANGE (-5490 3535);
FORCEPROP 2 LASTPIN (-5500 3575) $PN BH71
J 0
(-5490 3585);
DISPLAY 0.617021 (-5490 3585);
PAINT ORANGE (-5490 3585);
FORCEPROP 2 LASTPIN (-5500 3625) $PN BH69
J 0
(-5490 3635);
DISPLAY 0.617021 (-5490 3635);
PAINT ORANGE (-5490 3635);
FORCEPROP 2 LASTPIN (-5500 3675) $PN BH67
J 0
(-5490 3685);
DISPLAY 0.617021 (-5490 3685);
PAINT ORANGE (-5490 3685);
FORCEPROP 2 LASTPIN (-5500 3725) $PN BH65
J 0
(-5490 3735);
DISPLAY 0.617021 (-5490 3735);
PAINT ORANGE (-5490 3735);
FORCEPROP 2 LASTPIN (-5500 3775) $PN BH63
J 0
(-5490 3785);
DISPLAY 0.617021 (-5490 3785);
PAINT ORANGE (-5490 3785);
FORCEPROP 2 LASTPIN (-5500 3825) $PN BH61
J 0
(-5490 3835);
DISPLAY 0.617021 (-5490 3835);
PAINT ORANGE (-5490 3835);
FORCEPROP 2 LASTPIN (-5500 3875) $PN BG84
J 0
(-5490 3885);
DISPLAY 0.617021 (-5490 3885);
PAINT ORANGE (-5490 3885);
FORCEPROP 2 LASTPIN (-5500 3925) $PN BG70
J 0
(-5490 3935);
DISPLAY 0.617021 (-5490 3935);
PAINT ORANGE (-5490 3935);
FORCEPROP 2 LASTPIN (-5500 3975) $PN BG68
J 0
(-5490 3985);
DISPLAY 0.617021 (-5490 3985);
PAINT ORANGE (-5490 3985);
FORCEPROP 2 LASTPIN (-5500 4025) $PN BG66
J 0
(-5490 4035);
DISPLAY 0.617021 (-5490 4035);
PAINT ORANGE (-5490 4035);
FORCEPROP 2 LASTPIN (-5500 4075) $PN BG64
J 0
(-5490 4085);
DISPLAY 0.617021 (-5490 4085);
PAINT ORANGE (-5490 4085);
FORCEPROP 2 LASTPIN (-6900 4075) $PN AG40
J 2
(-6910 4085);
DISPLAY 0.617021 (-6910 4085);
PAINT ORANGE (-6910 4085);
FORCEPROP 2 LASTPIN (-6900 4125) $PN AG38
J 2
(-6910 4135);
DISPLAY 0.617021 (-6910 4135);
PAINT ORANGE (-6910 4135);
FORCEPROP 1 LAST MATERIAL IC
J 0
(-6850 4375);
DISPLAY 0.617021 (-6850 4375);
PAINT SKYBLUE (-6850 4375);
FORCEPROP 1 LAST LOCATION U5D1
J 0
(-6850 4425);
DISPLAY 0.617021 (-6850 4425);
PAINT AQUA (-6850 4425);
FORCEPROP 2 LASTPIN (-5500 4125) $PN BG62
J 0
(-5490 4135);
DISPLAY 0.617021 (-5490 4135);
PAINT ORANGE (-5490 4135);
FORCEPROP 2 LASTPIN (-5500 3175) $PN BJ62
J 0
(-5490 3185);
DISPLAY 0.617021 (-5490 3185);
PAINT ORANGE (-5490 3185);
FORCEPROP 2 LASTPIN (-6900 4175) $PN AF43
J 2
(-6910 4185);
DISPLAY 0.617021 (-6910 4185);
PAINT ORANGE (-6910 4185);
FORCEPROP 2 LASTPIN (-5500 4175) $PN BG60
J 0
(-5490 4185);
DISPLAY 0.617021 (-5490 4185);
PAINT ORANGE (-5490 4185);
FORCEPROP 2 LAST CDS_LIB chpset_lib
J 0
(-6200 2475);
PAINT ORANGE (-6200 2475);
DISPLAY INVISIBLE (-6200 2475);
FORCEPROP 1 LAST PACK_TYPE BGA1
J 0
(-6850 4475);
PAINT SKYBLUE (-6850 4475);
DISPLAY INVISIBLE (-6850 4475);
FORCEPROP 0 LAST ROOM CPU0
J 0
(-6850 4525);
DISPLAY 1.021277 (-6850 4525);
PAINT ORANGE (-6850 4525);
DISPLAY INVISIBLE (-6850 4525);
FORCEPROP 2 LAST CDS_LOCATION U5D1
J 0
(-6850 4425);
DISPLAY 0.617021 (-6850 4425);
PAINT AQUA (-6850 4425);
DISPLAY INVISIBLE (-6850 4425);
FORCEPROP 2 LAST SEC 18
J 0
(-6850 4475);
DISPLAY 0.680851 (-6850 4475);
PAINT MONO (-6850 4475);
DISPLAY INVISIBLE (-6850 4475);
FORCEPROP 2 LAST SEC_TYPE BGA1
J 0
(-6850 4475);
DISPLAY 1.021277 (-6850 4475);
PAINT ORANGE (-6850 4475);
DISPLAY INVISIBLE (-6850 4475);
FORCEPROP 1 LAST PATH I310
J 0
(-6200 4375);
PAINT GREEN (-6200 4375);
DISPLAY INVISIBLE (-6200 4375);
FORCEADD SKX_EXT_B..19
(-2425 2475);
FORCEPROP 2 LASTPIN (-1725 1525) $PN CU52
J 0
(-1715 1535);
DISPLAY 0.617021 (-1715 1535);
PAINT ORANGE (-1715 1535);
FORCEPROP 2 LASTPIN (-1725 1325) $PN CW48
J 0
(-1715 1335);
DISPLAY 0.617021 (-1715 1335);
PAINT ORANGE (-1715 1335);
FORCEPROP 2 LASTPIN (-3125 775) $PN BY83
J 2
(-3135 785);
DISPLAY 0.617021 (-3135 785);
PAINT ORANGE (-3135 785);
FORCEPROP 2 LASTPIN (-3125 825) $PN BY81
J 2
(-3135 835);
DISPLAY 0.617021 (-3135 835);
PAINT ORANGE (-3135 835);
FORCEPROP 2 LASTPIN (-3125 875) $PN BY79
J 2
(-3135 885);
DISPLAY 0.617021 (-3135 885);
PAINT ORANGE (-3135 885);
FORCEPROP 2 LASTPIN (-3125 925) $PN BY77
J 2
(-3135 935);
DISPLAY 0.617021 (-3135 935);
PAINT ORANGE (-3135 935);
FORCEPROP 2 LASTPIN (-3125 975) $PN BY75
J 2
(-3135 985);
DISPLAY 0.617021 (-3135 985);
PAINT ORANGE (-3135 985);
FORCEPROP 2 LASTPIN (-3125 1225) $PN BW68
J 2
(-3135 1235);
DISPLAY 0.617021 (-3135 1235);
PAINT ORANGE (-3135 1235);
FORCEPROP 2 LASTPIN (-3125 1175) $PN BW70
J 2
(-3135 1185);
DISPLAY 0.617021 (-3135 1185);
PAINT ORANGE (-3135 1185);
FORCEPROP 2 LASTPIN (-3125 1125) $PN BW84
J 2
(-3135 1135);
DISPLAY 0.617021 (-3135 1135);
PAINT ORANGE (-3135 1135);
FORCEPROP 2 LASTPIN (-3125 1075) $PN BY61
J 2
(-3135 1085);
DISPLAY 0.617021 (-3135 1085);
PAINT ORANGE (-3135 1085);
FORCEPROP 2 LASTPIN (-3125 1025) $PN BY73
J 2
(-3135 1035);
DISPLAY 0.617021 (-3135 1035);
PAINT ORANGE (-3135 1035);
FORCEPROP 2 LASTPIN (-3125 1475) $PN BV83
J 2
(-3135 1485);
DISPLAY 0.617021 (-3135 1485);
PAINT ORANGE (-3135 1485);
FORCEPROP 2 LASTPIN (-3125 1425) $PN BW60
J 2
(-3135 1435);
DISPLAY 0.617021 (-3135 1435);
PAINT ORANGE (-3135 1435);
FORCEPROP 2 LASTPIN (-3125 1375) $PN BW62
J 2
(-3135 1385);
DISPLAY 0.617021 (-3135 1385);
PAINT ORANGE (-3135 1385);
FORCEPROP 2 LASTPIN (-3125 1325) $PN BW64
J 2
(-3135 1335);
DISPLAY 0.617021 (-3135 1335);
PAINT ORANGE (-3135 1335);
FORCEPROP 2 LASTPIN (-3125 1275) $PN BW66
J 2
(-3135 1285);
DISPLAY 0.617021 (-3135 1285);
PAINT ORANGE (-3135 1285);
FORCEPROP 2 LASTPIN (-3125 1525) $PN BV81
J 2
(-3135 1535);
DISPLAY 0.617021 (-3135 1535);
PAINT ORANGE (-3135 1535);
FORCEPROP 2 LASTPIN (-3125 1725) $PN BV73
J 2
(-3135 1735);
DISPLAY 0.617021 (-3135 1735);
PAINT ORANGE (-3135 1735);
FORCEPROP 2 LASTPIN (-3125 1675) $PN BV75
J 2
(-3135 1685);
DISPLAY 0.617021 (-3135 1685);
PAINT ORANGE (-3135 1685);
FORCEPROP 2 LASTPIN (-3125 1625) $PN BV77
J 2
(-3135 1635);
DISPLAY 0.617021 (-3135 1635);
PAINT ORANGE (-3135 1635);
FORCEPROP 2 LASTPIN (-3125 1575) $PN BV79
J 2
(-3135 1585);
DISPLAY 0.617021 (-3135 1585);
PAINT ORANGE (-3135 1585);
FORCEPROP 2 LASTPIN (-3125 1775) $PN BV71
J 2
(-3135 1785);
DISPLAY 0.617021 (-3135 1785);
PAINT ORANGE (-3135 1785);
FORCEPROP 2 LASTPIN (-3125 1975) $PN BV63
J 2
(-3135 1985);
DISPLAY 0.617021 (-3135 1985);
PAINT ORANGE (-3135 1985);
FORCEPROP 2 LASTPIN (-3125 1925) $PN BV65
J 2
(-3135 1935);
DISPLAY 0.617021 (-3135 1935);
PAINT ORANGE (-3135 1935);
FORCEPROP 2 LASTPIN (-3125 1875) $PN BV67
J 2
(-3135 1885);
DISPLAY 0.617021 (-3135 1885);
PAINT ORANGE (-3135 1885);
FORCEPROP 2 LASTPIN (-3125 1825) $PN BV69
J 2
(-3135 1835);
DISPLAY 0.617021 (-3135 1835);
PAINT ORANGE (-3135 1835);
FORCEPROP 1 LAST PART_NUMBER TBD
J 0
(-3075 525);
DISPLAY 0.617021 (-3075 525);
PAINT BLUE (-3075 525);
FORCEPROP 2 LASTPIN (-3125 2025) $PN BV61
J 2
(-3135 2035);
DISPLAY 0.617021 (-3135 2035);
PAINT ORANGE (-3135 2035);
FORCEPROP 2 LASTPIN (-3125 2225) $PN BU78
J 2
(-3135 2235);
DISPLAY 0.617021 (-3135 2235);
PAINT ORANGE (-3135 2235);
FORCEPROP 2 LASTPIN (-3125 2175) $PN BU80
J 2
(-3135 2185);
DISPLAY 0.617021 (-3135 2185);
PAINT ORANGE (-3135 2185);
FORCEPROP 2 LASTPIN (-3125 2125) $PN BU82
J 2
(-3135 2135);
DISPLAY 0.617021 (-3135 2135);
PAINT ORANGE (-3135 2135);
FORCEPROP 2 LASTPIN (-3125 2075) $PN BU84
J 2
(-3135 2085);
DISPLAY 0.617021 (-3135 2085);
PAINT ORANGE (-3135 2085);
FORCEPROP 2 LASTPIN (-3125 2275) $PN BU76
J 2
(-3135 2285);
DISPLAY 0.617021 (-3135 2285);
PAINT ORANGE (-3135 2285);
FORCEPROP 2 LASTPIN (-3125 2475) $PN BU68
J 2
(-3135 2485);
DISPLAY 0.617021 (-3135 2485);
PAINT ORANGE (-3135 2485);
FORCEPROP 2 LASTPIN (-3125 2425) $PN BU70
J 2
(-3135 2435);
DISPLAY 0.617021 (-3135 2435);
PAINT ORANGE (-3135 2435);
FORCEPROP 2 LASTPIN (-3125 2375) $PN BU72
J 2
(-3135 2385);
DISPLAY 0.617021 (-3135 2385);
PAINT ORANGE (-3135 2385);
FORCEPROP 2 LASTPIN (-3125 2325) $PN BU74
J 2
(-3135 2335);
DISPLAY 0.617021 (-3135 2335);
PAINT ORANGE (-3135 2335);
FORCEPROP 2 LASTPIN (-3125 2525) $PN BU66
J 2
(-3135 2535);
DISPLAY 0.617021 (-3135 2535);
PAINT ORANGE (-3135 2535);
FORCEPROP 2 LASTPIN (-3125 2775) $PN BT81
J 2
(-3135 2785);
DISPLAY 0.617021 (-3135 2785);
PAINT ORANGE (-3135 2785);
FORCEPROP 2 LASTPIN (-3125 2725) $PN BT83
J 2
(-3135 2735);
DISPLAY 0.617021 (-3135 2735);
PAINT ORANGE (-3135 2735);
FORCEPROP 2 LASTPIN (-3125 2675) $PN BU60
J 2
(-3135 2685);
DISPLAY 0.617021 (-3135 2685);
PAINT ORANGE (-3135 2685);
FORCEPROP 2 LASTPIN (-3125 2625) $PN BU62
J 2
(-3135 2635);
DISPLAY 0.617021 (-3135 2635);
PAINT ORANGE (-3135 2635);
FORCEPROP 2 LASTPIN (-3125 2575) $PN BU64
J 2
(-3135 2585);
DISPLAY 0.617021 (-3135 2585);
PAINT ORANGE (-3135 2585);
FORCEPROP 2 LASTPIN (-3125 3025) $PN BT71
J 2
(-3135 3035);
DISPLAY 0.617021 (-3135 3035);
PAINT ORANGE (-3135 3035);
FORCEPROP 2 LASTPIN (-3125 2975) $PN BT73
J 2
(-3135 2985);
DISPLAY 0.617021 (-3135 2985);
PAINT ORANGE (-3135 2985);
FORCEPROP 2 LASTPIN (-3125 2925) $PN BT75
J 2
(-3135 2935);
DISPLAY 0.617021 (-3135 2935);
PAINT ORANGE (-3135 2935);
FORCEPROP 2 LASTPIN (-3125 2875) $PN BT77
J 2
(-3135 2885);
DISPLAY 0.617021 (-3135 2885);
PAINT ORANGE (-3135 2885);
FORCEPROP 2 LASTPIN (-3125 2825) $PN BT79
J 2
(-3135 2835);
DISPLAY 0.617021 (-3135 2835);
PAINT ORANGE (-3135 2835);
FORCEPROP 2 LASTPIN (-3125 3275) $PN BT61
J 2
(-3135 3285);
DISPLAY 0.617021 (-3135 3285);
PAINT ORANGE (-3135 3285);
FORCEPROP 2 LASTPIN (-3125 3225) $PN BT63
J 2
(-3135 3235);
DISPLAY 0.617021 (-3135 3235);
PAINT ORANGE (-3135 3235);
FORCEPROP 2 LASTPIN (-3125 3175) $PN BT65
J 2
(-3135 3185);
DISPLAY 0.617021 (-3135 3185);
PAINT ORANGE (-3135 3185);
FORCEPROP 2 LASTPIN (-3125 3125) $PN BT67
J 2
(-3135 3135);
DISPLAY 0.617021 (-3135 3135);
PAINT ORANGE (-3135 3135);
FORCEPROP 2 LASTPIN (-3125 3075) $PN BT69
J 2
(-3135 3085);
DISPLAY 0.617021 (-3135 3085);
PAINT ORANGE (-3135 3085);
FORCEPROP 2 LASTPIN (-3125 3525) $PN BP81
J 2
(-3135 3535);
DISPLAY 0.617021 (-3135 3535);
PAINT ORANGE (-3135 3535);
FORCEPROP 2 LASTPIN (-3125 3475) $PN BP83
J 2
(-3135 3485);
DISPLAY 0.617021 (-3135 3485);
PAINT ORANGE (-3135 3485);
FORCEPROP 2 LASTPIN (-3125 3425) $PN BR60
J 2
(-3135 3435);
DISPLAY 0.617021 (-3135 3435);
PAINT ORANGE (-3135 3435);
FORCEPROP 2 LASTPIN (-3125 3375) $PN BR62
J 2
(-3135 3385);
DISPLAY 0.617021 (-3135 3385);
PAINT ORANGE (-3135 3385);
FORCEPROP 2 LASTPIN (-3125 3325) $PN BR84
J 2
(-3135 3335);
DISPLAY 0.617021 (-3135 3335);
PAINT ORANGE (-3135 3335);
FORCEPROP 2 LASTPIN (-3125 3775) $PN BP71
J 2
(-3135 3785);
DISPLAY 0.617021 (-3135 3785);
PAINT ORANGE (-3135 3785);
FORCEPROP 2 LASTPIN (-3125 3725) $PN BP73
J 2
(-3135 3735);
DISPLAY 0.617021 (-3135 3735);
PAINT ORANGE (-3135 3735);
FORCEPROP 2 LASTPIN (-3125 3675) $PN BP75
J 2
(-3135 3685);
DISPLAY 0.617021 (-3135 3685);
PAINT ORANGE (-3135 3685);
FORCEPROP 2 LASTPIN (-3125 3625) $PN BP77
J 2
(-3135 3635);
DISPLAY 0.617021 (-3135 3635);
PAINT ORANGE (-3135 3635);
FORCEPROP 2 LASTPIN (-3125 3575) $PN BP79
J 2
(-3135 3585);
DISPLAY 0.617021 (-3135 3585);
PAINT ORANGE (-3135 3585);
FORCEPROP 2 LASTPIN (-3125 3825) $PN BP69
J 2
(-3135 3835);
DISPLAY 0.617021 (-3135 3835);
PAINT ORANGE (-3135 3835);
FORCEPROP 2 LASTPIN (-3125 4025) $PN BP61
J 2
(-3135 4035);
DISPLAY 0.617021 (-3135 4035);
PAINT ORANGE (-3135 4035);
FORCEPROP 2 LASTPIN (-3125 3975) $PN BP63
J 2
(-3135 3985);
DISPLAY 0.617021 (-3135 3985);
PAINT ORANGE (-3135 3985);
FORCEPROP 2 LASTPIN (-3125 3925) $PN BP65
J 2
(-3135 3935);
DISPLAY 0.617021 (-3135 3935);
PAINT ORANGE (-3135 3935);
FORCEPROP 2 LASTPIN (-3125 3875) $PN BP67
J 2
(-3135 3885);
DISPLAY 0.617021 (-3135 3885);
PAINT ORANGE (-3135 3885);
FORCEPROP 2 LASTPIN (-1725 725) $PN AY85
J 0
(-1715 735);
DISPLAY 0.617021 (-1715 735);
PAINT ORANGE (-1715 735);
FORCEPROP 2 LASTPIN (-1725 875) $PN AD41
J 0
(-1715 885);
DISPLAY 0.617021 (-1715 885);
PAINT ORANGE (-1715 885);
FORCEPROP 2 LASTPIN (-1725 975) $PN AW86
J 0
(-1715 985);
DISPLAY 0.617021 (-1715 985);
PAINT ORANGE (-1715 985);
FORCEPROP 2 LASTPIN (-1725 775) $PN BA86
J 0
(-1715 785);
DISPLAY 0.617021 (-1715 785);
PAINT ORANGE (-1715 785);
FORCEPROP 2 LASTPIN (-1725 1175) $PN CY49
J 0
(-1715 1185);
DISPLAY 0.617021 (-1715 1185);
PAINT ORANGE (-1715 1185);
FORCEPROP 2 LASTPIN (-1725 1225) $PN CY47
J 0
(-1715 1235);
DISPLAY 0.617021 (-1715 1235);
PAINT ORANGE (-1715 1235);
FORCEPROP 2 LASTPIN (-1725 1075) $PN AV85
J 0
(-1715 1085);
DISPLAY 0.617021 (-1715 1085);
PAINT ORANGE (-1715 1085);
FORCEPROP 2 LASTPIN (-1725 1475) $PN CU54
J 0
(-1715 1485);
DISPLAY 0.617021 (-1715 1485);
PAINT ORANGE (-1715 1485);
FORCEPROP 2 LASTPIN (-1725 1425) $PN CV51
J 0
(-1715 1435);
DISPLAY 0.617021 (-1715 1435);
PAINT ORANGE (-1715 1435);
FORCEPROP 2 LASTPIN (-1725 1375) $PN CW46
J 0
(-1715 1385);
DISPLAY 0.617021 (-1715 1385);
PAINT ORANGE (-1715 1385);
FORCEPROP 2 LASTPIN (-1725 1275) $PN CW50
J 0
(-1715 1285);
DISPLAY 0.617021 (-1715 1285);
PAINT ORANGE (-1715 1285);
FORCEPROP 2 LASTPIN (-1725 1725) $PN CT55
J 0
(-1715 1735);
DISPLAY 0.617021 (-1715 1735);
PAINT ORANGE (-1715 1735);
FORCEPROP 2 LASTPIN (-1725 1675) $PN CU38
J 0
(-1715 1685);
DISPLAY 0.617021 (-1715 1685);
PAINT ORANGE (-1715 1685);
FORCEPROP 2 LASTPIN (-1725 1625) $PN CU40
J 0
(-1715 1635);
DISPLAY 0.617021 (-1715 1635);
PAINT ORANGE (-1715 1635);
FORCEPROP 2 LASTPIN (-1725 1575) $PN CU42
J 0
(-1715 1585);
DISPLAY 0.617021 (-1715 1585);
PAINT ORANGE (-1715 1585);
FORCEPROP 2 LASTPIN (-1725 1775) $PN CT53
J 0
(-1715 1785);
DISPLAY 0.617021 (-1715 1785);
PAINT ORANGE (-1715 1785);
FORCEPROP 2 LASTPIN (-1725 1975) $PN CR56
J 0
(-1715 1985);
DISPLAY 0.617021 (-1715 1985);
PAINT ORANGE (-1715 1985);
FORCEPROP 2 LASTPIN (-1725 1925) $PN CT37
J 0
(-1715 1935);
DISPLAY 0.617021 (-1715 1935);
PAINT ORANGE (-1715 1935);
FORCEPROP 2 LASTPIN (-1725 1875) $PN CT39
J 0
(-1715 1885);
DISPLAY 0.617021 (-1715 1885);
PAINT ORANGE (-1715 1885);
FORCEPROP 2 LASTPIN (-1725 1825) $PN CT41
J 0
(-1715 1835);
DISPLAY 0.617021 (-1715 1835);
PAINT ORANGE (-1715 1835);
FORCEPROP 2 LASTPIN (-1725 2025) $PN CR54
J 0
(-1715 2035);
DISPLAY 0.617021 (-1715 2035);
PAINT ORANGE (-1715 2035);
FORCEPROP 2 LASTPIN (-1725 2225) $PN CP33
J 0
(-1715 2235);
DISPLAY 0.617021 (-1715 2235);
PAINT ORANGE (-1715 2235);
FORCEPROP 2 LASTPIN (-1725 2175) $PN CP55
J 0
(-1715 2185);
DISPLAY 0.617021 (-1715 2185);
PAINT ORANGE (-1715 2185);
FORCEPROP 2 LASTPIN (-1725 2125) $PN CP57
J 0
(-1715 2135);
DISPLAY 0.617021 (-1715 2135);
PAINT ORANGE (-1715 2135);
FORCEPROP 2 LASTPIN (-1725 2075) $PN CR34
J 0
(-1715 2085);
DISPLAY 0.617021 (-1715 2085);
PAINT ORANGE (-1715 2085);
FORCEPROP 2 LASTPIN (-1725 2275) $PN CN58
J 0
(-1715 2285);
DISPLAY 0.617021 (-1715 2285);
PAINT ORANGE (-1715 2285);
FORCEPROP 2 LASTPIN (-1725 2475) $PN CL60
J 0
(-1715 2485);
DISPLAY 0.617021 (-1715 2485);
PAINT ORANGE (-1715 2485);
FORCEPROP 2 LASTPIN (-1725 2425) $PN CM57
J 0
(-1715 2435);
DISPLAY 0.617021 (-1715 2435);
PAINT ORANGE (-1715 2435);
FORCEPROP 2 LASTPIN (-1725 2375) $PN CM59
J 0
(-1715 2385);
DISPLAY 0.617021 (-1715 2385);
PAINT ORANGE (-1715 2385);
FORCEPROP 2 LASTPIN (-1725 2325) $PN CN56
J 0
(-1715 2335);
DISPLAY 0.617021 (-1715 2335);
PAINT ORANGE (-1715 2335);
FORCEPROP 2 LASTPIN (-1725 2525) $PN CL58
J 0
(-1715 2535);
DISPLAY 0.617021 (-1715 2535);
PAINT ORANGE (-1715 2535);
FORCEPROP 2 LASTPIN (-1725 2775) $PN CH61
J 0
(-1715 2785);
DISPLAY 0.617021 (-1715 2785);
PAINT ORANGE (-1715 2785);
FORCEPROP 2 LASTPIN (-1725 2725) $PN CH85
J 0
(-1715 2735);
DISPLAY 0.617021 (-1715 2735);
PAINT ORANGE (-1715 2735);
FORCEPROP 2 LASTPIN (-1725 2675) $PN CJ60
J 0
(-1715 2685);
DISPLAY 0.617021 (-1715 2685);
PAINT ORANGE (-1715 2685);
FORCEPROP 2 LASTPIN (-1725 2625) $PN CK59
J 0
(-1715 2635);
DISPLAY 0.617021 (-1715 2635);
PAINT ORANGE (-1715 2635);
FORCEPROP 2 LASTPIN (-1725 2575) $PN CK61
J 0
(-1715 2585);
DISPLAY 0.617021 (-1715 2585);
PAINT ORANGE (-1715 2585);
FORCEPROP 2 LASTPIN (-1725 3025) $PN CE84
J 0
(-1715 3035);
DISPLAY 0.617021 (-1715 3035);
PAINT ORANGE (-1715 3035);
FORCEPROP 2 LASTPIN (-1725 2975) $PN CF61
J 0
(-1715 2985);
DISPLAY 0.617021 (-1715 2985);
PAINT ORANGE (-1715 2985);
FORCEPROP 2 LASTPIN (-1725 2925) $PN CF85
J 0
(-1715 2935);
DISPLAY 0.617021 (-1715 2935);
PAINT ORANGE (-1715 2935);
FORCEPROP 2 LASTPIN (-1725 2875) $PN CG60
J 0
(-1715 2885);
DISPLAY 0.617021 (-1715 2885);
PAINT ORANGE (-1715 2885);
FORCEPROP 2 LASTPIN (-1725 2825) $PN CG84
J 0
(-1715 2835);
DISPLAY 0.617021 (-1715 2835);
PAINT ORANGE (-1715 2835);
FORCEPROP 2 LASTPIN (-1725 3275) $PN CC84
J 0
(-1715 3285);
DISPLAY 0.617021 (-1715 3285);
PAINT ORANGE (-1715 3285);
FORCEPROP 2 LASTPIN (-1725 3225) $PN CD61
J 0
(-1715 3235);
DISPLAY 0.617021 (-1715 3235);
PAINT ORANGE (-1715 3235);
FORCEPROP 2 LASTPIN (-1725 3175) $PN CD83
J 0
(-1715 3185);
DISPLAY 0.617021 (-1715 3185);
PAINT ORANGE (-1715 3185);
FORCEPROP 2 LASTPIN (-1725 3125) $PN CD85
J 0
(-1715 3135);
DISPLAY 0.617021 (-1715 3135);
PAINT ORANGE (-1715 3135);
FORCEPROP 2 LASTPIN (-1725 3075) $PN CE60
J 0
(-1715 3085);
DISPLAY 0.617021 (-1715 3085);
PAINT ORANGE (-1715 3085);
FORCEPROP 2 LASTPIN (-1725 3525) $PN CB79
J 0
(-1715 3535);
DISPLAY 0.617021 (-1715 3535);
PAINT ORANGE (-1715 3535);
FORCEPROP 2 LASTPIN (-1725 3475) $PN CB81
J 0
(-1715 3485);
DISPLAY 0.617021 (-1715 3485);
PAINT ORANGE (-1715 3485);
FORCEPROP 2 LASTPIN (-1725 3425) $PN CB83
J 0
(-1715 3435);
DISPLAY 0.617021 (-1715 3435);
PAINT ORANGE (-1715 3435);
FORCEPROP 2 LASTPIN (-1725 3375) $PN CC60
J 0
(-1715 3385);
DISPLAY 0.617021 (-1715 3385);
PAINT ORANGE (-1715 3385);
FORCEPROP 2 LASTPIN (-1725 3325) $PN CC62
J 0
(-1715 3335);
DISPLAY 0.617021 (-1715 3335);
PAINT ORANGE (-1715 3335);
FORCEPROP 2 LASTPIN (-1725 3775) $PN CA84
J 0
(-1715 3785);
DISPLAY 0.617021 (-1715 3785);
PAINT ORANGE (-1715 3785);
FORCEPROP 2 LASTPIN (-1725 3725) $PN CB61
J 0
(-1715 3735);
DISPLAY 0.617021 (-1715 3735);
PAINT ORANGE (-1715 3735);
FORCEPROP 2 LASTPIN (-1725 3675) $PN CB73
J 0
(-1715 3685);
DISPLAY 0.617021 (-1715 3685);
PAINT ORANGE (-1715 3685);
FORCEPROP 2 LASTPIN (-1725 3625) $PN CB75
J 0
(-1715 3635);
DISPLAY 0.617021 (-1715 3635);
PAINT ORANGE (-1715 3635);
FORCEPROP 2 LASTPIN (-1725 3575) $PN CB77
J 0
(-1715 3585);
DISPLAY 0.617021 (-1715 3585);
PAINT ORANGE (-1715 3585);
FORCEPROP 2 LASTPIN (-1725 3825) $PN CA82
J 0
(-1715 3835);
DISPLAY 0.617021 (-1715 3835);
PAINT ORANGE (-1715 3835);
FORCEPROP 2 LASTPIN (-1725 4025) $PN CA74
J 0
(-1715 4035);
DISPLAY 0.617021 (-1715 4035);
PAINT ORANGE (-1715 4035);
FORCEPROP 2 LASTPIN (-1725 3925) $PN CA78
J 0
(-1715 3935);
DISPLAY 0.617021 (-1715 3935);
PAINT ORANGE (-1715 3935);
FORCEPROP 2 LASTPIN (-1725 3875) $PN CA80
J 0
(-1715 3885);
DISPLAY 0.617021 (-1715 3885);
PAINT ORANGE (-1715 3885);
FORCEPROP 2 LASTPIN (-1725 4075) $PN CA72
J 0
(-1715 4085);
DISPLAY 0.617021 (-1715 4085);
PAINT ORANGE (-1715 4085);
FORCEPROP 2 LASTPIN (-3125 4075) $PN BN84
J 2
(-3135 4085);
DISPLAY 0.617021 (-3135 4085);
PAINT ORANGE (-3135 4085);
FORCEPROP 2 LASTPIN (-3125 4125) $PN BN82
J 2
(-3135 4135);
DISPLAY 0.617021 (-3135 4135);
PAINT ORANGE (-3135 4135);
FORCEPROP 2 LASTPIN (-3125 4175) $PN BN80
J 2
(-3135 4185);
DISPLAY 0.617021 (-3135 4185);
PAINT ORANGE (-3135 4185);
FORCEPROP 1 LAST MATERIAL IC
J 0
(-3075 4375);
DISPLAY 0.617021 (-3075 4375);
PAINT SKYBLUE (-3075 4375);
FORCEPROP 1 LAST LOCATION U5D1
J 0
(-3075 4425);
DISPLAY 0.617021 (-3075 4425);
PAINT AQUA (-3075 4425);
FORCEPROP 2 LASTPIN (-1725 4125) $PN CA62
J 0
(-1715 4135);
DISPLAY 0.617021 (-1715 4135);
PAINT ORANGE (-1715 4135);
FORCEPROP 2 LASTPIN (-1725 4175) $PN CA60
J 0
(-1715 4185);
DISPLAY 0.617021 (-1715 4185);
PAINT ORANGE (-1715 4185);
FORCEPROP 2 LASTPIN (-1725 3975) $PN CA76
J 0
(-1715 3985);
DISPLAY 0.617021 (-1715 3985);
PAINT ORANGE (-1715 3985);
FORCEPROP 2 LAST CDS_LIB chpset_lib
J 0
(-2425 2475);
PAINT ORANGE (-2425 2475);
DISPLAY INVISIBLE (-2425 2475);
FORCEPROP 0 LAST ROOM CPU0
J 0
(-3075 4525);
DISPLAY 1.021277 (-3075 4525);
PAINT ORANGE (-3075 4525);
DISPLAY INVISIBLE (-3075 4525);
FORCEPROP 2 LAST CDS_LOCATION U5D1
J 0
(-3075 4425);
DISPLAY 0.617021 (-3075 4425);
PAINT AQUA (-3075 4425);
DISPLAY INVISIBLE (-3075 4425);
FORCEPROP 2 LAST SEC 19
J 0
(-3075 4475);
DISPLAY 0.680851 (-3075 4475);
PAINT MONO (-3075 4475);
DISPLAY INVISIBLE (-3075 4475);
FORCEPROP 2 LAST SEC_TYPE BGA1
J 0
(-3075 4475);
DISPLAY 1.021277 (-3075 4475);
PAINT ORANGE (-3075 4475);
DISPLAY INVISIBLE (-3075 4475);
FORCEPROP 1 LAST PACK_TYPE BGA1
J 0
(-3075 4475);
PAINT SKYBLUE (-3075 4475);
DISPLAY INVISIBLE (-3075 4475);
FORCEPROP 1 LAST PATH I311
J 0
(-2425 4375);
PAINT GREEN (-2425 4375);
DISPLAY INVISIBLE (-2425 4375);
FORCEADD RES..2
(-375 1125);
FORCEPROP 1 LAST LOCATION R5D6
J 0
(-330 1250);
DISPLAY 0.617021 (-330 1250);
PAINT AQUA (-330 1250);
FORCEPROP 1 LAST VALUE 10.0
J 0
(-330 1200);
DISPLAY 0.617021 (-330 1200);
PAINT SKYBLUE (-330 1200);
FORCEPROP 1 LAST PART_NUMBER G21796-066
J 0
(-335 1000);
DISPLAY 0.617021 (-335 1000);
PAINT BLUE (-335 1000);
FORCEPROP 1 LAST PACK_TYPE 0402
J 0
(-335 950);
DISPLAY 0.617021 (-335 950);
PAINT SKYBLUE (-335 950);
FORCEPROP 1 LASTPIN (-375 1025) $PN 2
J 0
(-370 1035);
DISPLAY 0.617021 (-370 1035);
PAINT ORANGE (-370 1035);
FORCEPROP 1 LAST TOLERANCE 1%
J 0
(-330 1150);
DISPLAY 0.617021 (-330 1150);
PAINT SKYBLUE (-330 1150);
FORCEPROP 1 LASTPIN (-375 1225) $PN 1
J 0
(-370 1187);
DISPLAY 0.617021 (-370 1187);
PAINT ORANGE (-370 1187);
FORCEPROP 1 LAST WATTAGE 1/16W
J 0
(-335 1100);
DISPLAY 0.617021 (-335 1100);
PAINT SKYBLUE (-335 1100);
FORCEPROP 1 LAST MATERIAL EMPTY
J 0
(-335 1050);
DISPLAY 0.617021 (-335 1050);
PAINT RED (-335 1050);
FORCEPROP 2 LAST CDS_LIB mstr_discrete
J 0
(-375 1125);
PAINT ORANGE (-375 1125);
DISPLAY INVISIBLE (-375 1125);
FORCEPROP 0 LAST ROOM CPU0
J 0
(-325 1350);
DISPLAY 1.021277 (-325 1350);
PAINT ORANGE (-325 1350);
DISPLAY INVISIBLE (-325 1350);
FORCEPROP 1 LAST PATH I312
J 0
(-325 1300);
DISPLAY 0.978723 (-325 1300);
PAINT WHITE (-325 1300);
DISPLAY INVISIBLE (-325 1300);
FORCEPROP 2 LAST SEC 1
J 0
(-325 1350);
DISPLAY 0.680851 (-325 1350);
PAINT MONO (-325 1350);
DISPLAY INVISIBLE (-325 1350);
FORCEPROP 2 LAST SEC_TYPE 0402
J 0
(-325 1350);
DISPLAY 1.021277 (-325 1350);
PAINT ORANGE (-325 1350);
DISPLAY INVISIBLE (-325 1350);
FORCEADD PVCCIO_CPU0..1
(-375 1450);
FORCEPROP 3 LASTPIN (-375 1400) SIG_NAME PVCCIO_CPU0\g
J 0
(-365 1410);
DISPLAY 0.659574 (-365 1410);
PAINT MONO (-365 1410);
DISPLAY INVISIBLE (-365 1410);
FORCEPROP 1 LAST PATH I313
J 0
(-325 1475);
DISPLAY 0.872340 (-325 1475);
PAINT AQUA (-325 1475);
DISPLAY INVISIBLE (-325 1475);
FORCEPROP 1 LAST BODY_TYPE PLUMBING
J 0
(-420 1407);
DISPLAY 0.340426 (-420 1407);
PAINT GREEN (-420 1407);
DISPLAY INVISIBLE (-420 1407);
FORCEPROP 2 LAST CDS_LIB mstr_symbols
J 0
(-375 1450);
PAINT ORANGE (-375 1450);
DISPLAY INVISIBLE (-375 1450);
FORCEPROP 1 LAST VOLTAGE 1.1V
J 0
(-420 1407);
DISPLAY 0.340426 (-420 1407);
PAINT SKYBLUE (-420 1407);
DISPLAY INVISIBLE (-420 1407);
FORCEPROP 1 LAST HDL_POWER PVCCIO_CPU0
J 1
(-375 1500);
DISPLAY 0.872340 (-375 1500);
PAINT GREEN (-375 1500);
DISPLAY INVISIBLE (-375 1500);
FORCEADD DNS..2
(-370 1120);
PAINT RED (-370 1120);
FORCEPROP 1 LAST COMMENT_BODY TRUE
R 1
J 0
(-295 895);
DISPLAY 0.872340 (-295 895);
PAINT GREEN (-295 895);
DISPLAY INVISIBLE (-295 895);
FORCEPROP 2 LAST CDS_LIB mstr_misc
J 0
(-370 1120);
PAINT ORANGE (-370 1120);
DISPLAY INVISIBLE (-370 1120);
FORCEADD DESIGN_NOTE..1
(-5200 550);
FORCEPROP 0 LAST L1 CPU SYMBOLS 1-30 ARE PRELIMINARY AND SUBJECT TO CHANGE
J 0
(-5400 425);
DISPLAY 1.021277 (-5400 425);
PAINT ORANGE (-5400 425);
FORCEPROP 2 LAST CDS_LIB mstr_symbols
J 0
(-5200 550);
PAINT ORANGE (-5200 550);
DISPLAY INVISIBLE (-5200 550);
FORCEPROP 1 LAST COMMENT_BODY TRUE
J 0
(-5175 650);
DISPLAY 0.978723 (-5175 650);
PAINT ORANGE (-5175 650);
DISPLAY INVISIBLE (-5175 650);
FORCEADD INTEL_CORP_BPAGE..1
(25 -25);
FORCEPROP 1 LAST CDS_CON_LAST_MODIFIED Fri Jun 16 17:48:14 2017
J 0
(-1400 300);
PAINT ORANGE (-1400 300);
DISPLAY INVISIBLE (-1400 300);
FORCEPROP 1 LAST CUSTOM_TXT_CDS <CURRENT_DESIGN_SHEET> OF <TOTAL_DESIGN_SHEETS>
J 0
(-475 0);
PAINT ORANGE (-475 0);
FORCEPROP 1 LAST CUSTOM_TXT_CDS <CON_LAST_MODIFIED>
J 0
(-3975 75);
PAINT ORANGE (-3975 75);
FORCEPROP 2 LAST CUSTOM_TXT_CDS <XR_PAGE_TITLE>
J 0
(-7865 5225);
DISPLAY 0.638298 (-7865 5225);
PAINT PINK (-7865 5225);
DISPLAY INVISIBLE (-7865 5225);
FORCEPROP 1 LAST SCH_TITLE SKYLAKE - SKT0 - 17 OF 21
J 0
(-7925 25);
DISPLAY 1.212766 (-7925 25);
PAINT GREEN (-7925 25);
FORCEPROP 2 LAST PAGE_BORDER TRUE
J 0
(-7865 5225);
DISPLAY 0.851064 (-7865 5225);
PAINT PINK (-7865 5225);
DISPLAY INVISIBLE (-7865 5225);
FORCEPROP 1 LAST COMMENT_BODY TRUE
J 0
(37 -13);
DISPLAY 0.638298 (37 -13);
PAINT GREEN (37 -13);
DISPLAY INVISIBLE (37 -13);
FORCEPROP 2 LAST CDS_LIB mstr_symbols
J 0
(25 -25);
PAINT ORANGE (25 -25);
DISPLAY INVISIBLE (25 -25);
FORCEPROP 2 LAST CDS_XR_PAGE_TITLE CR-37 : @BASEBOARD_FAB2_LIB.BASEBOARD_FAB2(SCH_1):PAGE37
J 0
(-7865 5225);
DISPLAY 0.638298 (-7865 5225);
PAINT PINK (-7865 5225);
DISPLAY INVISIBLE (-7865 5225);
FORCEADD PRELIM..10
(-6190 2465);
PAINT GRAY (-6190 2465);
FORCEPROP 1 LAST COMMENT_BODY TRUE
J 0
(-6190 2465);
PAINT ORANGE (-6190 2465);
DISPLAY INVISIBLE (-6190 2465);
FORCEPROP 2 LAST CDS_LIB mstr_misc
J 0
(-6190 2465);
PAINT ORANGE (-6190 2465);
DISPLAY INVISIBLE (-6190 2465);
WIRE 16 -1 (-7125 4300)(-7125 4175);
WIRE 16 -1 (-7125 4175)(-7125 4125);
WIRE 16 -1 (-7125 4175)(-6900 4175);
WIRE 16 -1 (-7125 4125)(-7125 4075);
WIRE 16 -1 (-7125 4125)(-6900 4125);
WIRE 16 -1 (-7125 4075)(-7125 4025);
WIRE 16 -1 (-7125 4075)(-6900 4075);
WIRE 16 -1 (-7125 4025)(-7125 3975);
WIRE 16 -1 (-7125 4025)(-6900 4025);
WIRE 16 -1 (-7125 3975)(-7125 3925);
WIRE 16 -1 (-7125 3975)(-6900 3975);
WIRE 16 -1 (-7125 3925)(-7125 3875);
WIRE 16 -1 (-7125 3925)(-6900 3925);
WIRE 16 -1 (-7125 3875)(-7125 3825);
WIRE 16 -1 (-7125 3875)(-6900 3875);
WIRE 16 -1 (-7125 3825)(-7125 3775);
WIRE 16 -1 (-7125 3825)(-6900 3825);
WIRE 16 -1 (-7125 3775)(-7125 3725);
WIRE 16 -1 (-7125 3775)(-6900 3775);
WIRE 16 -1 (-7125 3725)(-7125 3675);
WIRE 16 -1 (-7125 3725)(-6900 3725);
WIRE 16 -1 (-7125 3675)(-7125 3625);
WIRE 16 -1 (-7125 3675)(-6900 3675);
WIRE 16 -1 (-7125 3625)(-7125 3575);
WIRE 16 -1 (-7125 3625)(-6900 3625);
WIRE 16 -1 (-7125 3575)(-7125 3525);
WIRE 16 -1 (-7125 3575)(-6900 3575);
WIRE 16 -1 (-7125 3525)(-7125 3475);
WIRE 16 -1 (-7125 3525)(-6900 3525);
WIRE 16 -1 (-7125 3475)(-7125 3425);
WIRE 16 -1 (-7125 3475)(-6900 3475);
WIRE 16 -1 (-7125 3425)(-7125 3375);
WIRE 16 -1 (-7125 3425)(-6900 3425);
WIRE 16 -1 (-7125 3375)(-7125 3325);
WIRE 16 -1 (-7125 3375)(-6900 3375);
WIRE 16 -1 (-7125 3325)(-7125 3275);
WIRE 16 -1 (-7125 3325)(-6900 3325);
WIRE 16 -1 (-7125 3275)(-7125 3225);
WIRE 16 -1 (-7125 3275)(-6900 3275);
WIRE 16 -1 (-7125 3225)(-7125 3175);
WIRE 16 -1 (-7125 3225)(-6900 3225);
WIRE 16 -1 (-7125 3175)(-7125 3125);
WIRE 16 -1 (-7125 3175)(-6900 3175);
WIRE 16 -1 (-7125 3125)(-7125 3075);
WIRE 16 -1 (-7125 3125)(-6900 3125);
WIRE 16 -1 (-7125 3075)(-7125 3025);
WIRE 16 -1 (-7125 3075)(-6900 3075);
WIRE 16 -1 (-7125 3025)(-7125 2975);
WIRE 16 -1 (-7125 3025)(-6900 3025);
WIRE 16 -1 (-7125 2975)(-7125 2925);
WIRE 16 -1 (-7125 2975)(-6900 2975);
WIRE 16 -1 (-7125 2925)(-7125 2875);
WIRE 16 -1 (-7125 2925)(-6900 2925);
WIRE 16 -1 (-7125 2875)(-7125 2825);
WIRE 16 -1 (-7125 2875)(-6900 2875);
WIRE 16 -1 (-7125 2825)(-7125 2775);
WIRE 16 -1 (-7125 2825)(-6900 2825);
WIRE 16 -1 (-7125 2775)(-7125 2725);
WIRE 16 -1 (-7125 2775)(-6900 2775);
WIRE 16 -1 (-7125 2725)(-7125 2675);
WIRE 16 -1 (-7125 2725)(-6900 2725);
WIRE 16 -1 (-7125 2675)(-7125 2625);
WIRE 16 -1 (-7125 2675)(-6900 2675);
WIRE 16 -1 (-7125 2625)(-7125 2575);
WIRE 16 -1 (-7125 2625)(-6900 2625);
WIRE 16 -1 (-7125 2575)(-7125 2525);
WIRE 16 -1 (-7125 2575)(-6900 2575);
WIRE 16 -1 (-7125 2525)(-7125 2475);
WIRE 16 -1 (-7125 2525)(-6900 2525);
WIRE 16 -1 (-7125 2475)(-7125 2425);
WIRE 16 -1 (-7125 2475)(-6900 2475);
WIRE 16 -1 (-7125 2425)(-7125 2375);
WIRE 16 -1 (-7125 2425)(-6900 2425);
WIRE 16 -1 (-7125 2375)(-7125 2325);
WIRE 16 -1 (-7125 2375)(-6900 2375);
WIRE 16 -1 (-7125 2325)(-7125 2275);
WIRE 16 -1 (-7125 2325)(-6900 2325);
WIRE 16 -1 (-7125 2275)(-7125 2225);
WIRE 16 -1 (-7125 2275)(-6900 2275);
WIRE 16 -1 (-7125 2225)(-7125 2175);
WIRE 16 -1 (-7125 2225)(-6900 2225);
WIRE 16 -1 (-7125 2175)(-7125 2125);
WIRE 16 -1 (-7125 2175)(-6900 2175);
WIRE 16 -1 (-7125 2125)(-7125 2075);
WIRE 16 -1 (-7125 2125)(-6900 2125);
WIRE 16 -1 (-7125 2075)(-7125 2025);
WIRE 16 -1 (-7125 2075)(-6900 2075);
WIRE 16 -1 (-7125 2025)(-7125 1975);
WIRE 16 -1 (-7125 2025)(-6900 2025);
WIRE 16 -1 (-7125 1975)(-7125 1925);
WIRE 16 -1 (-7125 1975)(-6900 1975);
WIRE 16 -1 (-7125 1925)(-7125 1875);
WIRE 16 -1 (-7125 1925)(-6900 1925);
WIRE 16 -1 (-7125 1875)(-7125 1825);
WIRE 16 -1 (-7125 1875)(-6900 1875);
WIRE 16 -1 (-7125 1825)(-7125 1775);
WIRE 16 -1 (-7125 1825)(-6900 1825);
WIRE 16 -1 (-7125 1775)(-7125 1725);
WIRE 16 -1 (-7125 1775)(-6900 1775);
WIRE 16 -1 (-7125 1725)(-7125 1675);
WIRE 16 -1 (-7125 1725)(-6900 1725);
WIRE 16 -1 (-7125 1675)(-7125 1625);
WIRE 16 -1 (-7125 1675)(-6900 1675);
WIRE 16 -1 (-7125 1625)(-7125 1575);
WIRE 16 -1 (-7125 1625)(-6900 1625);
WIRE 16 -1 (-7125 1575)(-7125 1525);
WIRE 16 -1 (-7125 1575)(-6900 1575);
WIRE 16 -1 (-7125 1525)(-7125 1475);
WIRE 16 -1 (-7125 1525)(-6900 1525);
WIRE 16 -1 (-7125 1475)(-7125 1425);
WIRE 16 -1 (-7125 1475)(-6900 1475);
WIRE 16 -1 (-7125 1425)(-7125 1375);
WIRE 16 -1 (-7125 1425)(-6900 1425);
WIRE 16 -1 (-7125 1375)(-7125 1325);
WIRE 16 -1 (-7125 1375)(-6900 1375);
WIRE 16 -1 (-7125 1325)(-7125 1275);
WIRE 16 -1 (-7125 1325)(-6900 1325);
WIRE 16 -1 (-7125 1275)(-7125 1225);
WIRE 16 -1 (-7125 1275)(-6900 1275);
WIRE 16 -1 (-7125 1225)(-7125 1175);
WIRE 16 -1 (-7125 1225)(-6900 1225);
WIRE 16 -1 (-7125 1175)(-7125 1125);
WIRE 16 -1 (-7125 1175)(-6900 1175);
WIRE 16 -1 (-7125 1125)(-7125 1075);
WIRE 16 -1 (-7125 1125)(-6900 1125);
WIRE 16 -1 (-7125 1075)(-7125 1025);
WIRE 16 -1 (-7125 1075)(-6900 1075);
WIRE 16 -1 (-7125 1025)(-7125 975);
WIRE 16 -1 (-7125 1025)(-6900 1025);
WIRE 16 -1 (-7125 975)(-7125 925);
WIRE 16 -1 (-7125 975)(-6900 975);
WIRE 16 -1 (-7125 925)(-7125 875);
WIRE 16 -1 (-7125 925)(-6900 925);
WIRE 16 -1 (-7125 875)(-7125 825);
WIRE 16 -1 (-7125 875)(-6900 875);
WIRE 16 -1 (-7125 825)(-7125 775);
WIRE 16 -1 (-7125 825)(-6900 825);
WIRE 16 -1 (-7125 775)(-6900 775);
WIRE 16 -1 (-5250 4225)(-5250 4175);
WIRE 16 -1 (-5250 4175)(-5250 4125);
WIRE 16 -1 (-5250 4175)(-5500 4175);
WIRE 16 -1 (-5250 4125)(-5250 4075);
WIRE 16 -1 (-5250 4125)(-5500 4125);
WIRE 16 -1 (-5250 4075)(-5250 4025);
WIRE 16 -1 (-5250 4075)(-5500 4075);
WIRE 16 -1 (-5250 4025)(-5250 3975);
WIRE 16 -1 (-5250 4025)(-5500 4025);
WIRE 16 -1 (-5250 3975)(-5250 3925);
WIRE 16 -1 (-5250 3975)(-5500 3975);
WIRE 16 -1 (-5250 3925)(-5250 3875);
WIRE 16 -1 (-5250 3925)(-5500 3925);
WIRE 16 -1 (-5250 3875)(-5250 3825);
WIRE 16 -1 (-5250 3875)(-5500 3875);
WIRE 16 -1 (-5250 3825)(-5250 3775);
WIRE 16 -1 (-5250 3825)(-5500 3825);
WIRE 16 -1 (-5250 3775)(-5250 3725);
WIRE 16 -1 (-5250 3775)(-5500 3775);
WIRE 16 -1 (-5250 3725)(-5250 3675);
WIRE 16 -1 (-5250 3725)(-5500 3725);
WIRE 16 -1 (-5250 3675)(-5250 3625);
WIRE 16 -1 (-5250 3675)(-5500 3675);
WIRE 16 -1 (-5250 3625)(-5250 3575);
WIRE 16 -1 (-5250 3625)(-5500 3625);
WIRE 16 -1 (-5250 3575)(-5250 3525);
WIRE 16 -1 (-5250 3575)(-5500 3575);
WIRE 16 -1 (-5250 3525)(-5250 3475);
WIRE 16 -1 (-5250 3525)(-5500 3525);
WIRE 16 -1 (-5250 3475)(-5250 3425);
WIRE 16 -1 (-5250 3475)(-5500 3475);
WIRE 16 -1 (-5250 3425)(-5250 3375);
WIRE 16 -1 (-5250 3425)(-5500 3425);
WIRE 16 -1 (-5250 3375)(-5250 3325);
WIRE 16 -1 (-5250 3375)(-5500 3375);
WIRE 16 -1 (-5250 3325)(-5250 3275);
WIRE 16 -1 (-5250 3325)(-5500 3325);
WIRE 16 -1 (-5250 3275)(-5250 3225);
WIRE 16 -1 (-5250 3275)(-5500 3275);
WIRE 16 -1 (-5250 3225)(-5250 3175);
WIRE 16 -1 (-5250 3225)(-5500 3225);
WIRE 16 -1 (-5250 3175)(-5250 3125);
WIRE 16 -1 (-5250 3175)(-5500 3175);
WIRE 16 -1 (-5250 3125)(-5250 3075);
WIRE 16 -1 (-5250 3125)(-5500 3125);
WIRE 16 -1 (-5250 3075)(-5250 3025);
WIRE 16 -1 (-5250 3075)(-5500 3075);
WIRE 16 -1 (-5250 3025)(-5250 2975);
WIRE 16 -1 (-5250 3025)(-5500 3025);
WIRE 16 -1 (-5250 2975)(-5250 2925);
WIRE 16 -1 (-5250 2975)(-5500 2975);
WIRE 16 -1 (-5250 2925)(-5250 2875);
WIRE 16 -1 (-5250 2925)(-5500 2925);
WIRE 16 -1 (-5250 2875)(-5250 2825);
WIRE 16 -1 (-5250 2875)(-5500 2875);
WIRE 16 -1 (-5250 2825)(-5250 2775);
WIRE 16 -1 (-5250 2825)(-5500 2825);
WIRE 16 -1 (-5250 2775)(-5250 2725);
WIRE 16 -1 (-5250 2775)(-5500 2775);
WIRE 16 -1 (-5250 2725)(-5250 2675);
WIRE 16 -1 (-5250 2725)(-5500 2725);
WIRE 16 -1 (-5250 2675)(-5250 2625);
WIRE 16 -1 (-5250 2675)(-5500 2675);
WIRE 16 -1 (-5250 2625)(-5250 2575);
WIRE 16 -1 (-5250 2625)(-5500 2625);
WIRE 16 -1 (-5250 2575)(-5250 2525);
WIRE 16 -1 (-5250 2575)(-5500 2575);
WIRE 16 -1 (-5250 2525)(-5250 2475);
WIRE 16 -1 (-5250 2525)(-5500 2525);
WIRE 16 -1 (-5250 2475)(-5250 2425);
WIRE 16 -1 (-5250 2475)(-5500 2475);
WIRE 16 -1 (-5250 2425)(-5250 2375);
WIRE 16 -1 (-5250 2425)(-5500 2425);
WIRE 16 -1 (-5250 2375)(-5250 2325);
WIRE 16 -1 (-5250 2375)(-5500 2375);
WIRE 16 -1 (-5250 2325)(-5250 2275);
WIRE 16 -1 (-5250 2325)(-5500 2325);
WIRE 16 -1 (-5250 2275)(-5250 2225);
WIRE 16 -1 (-5250 2275)(-5500 2275);
WIRE 16 -1 (-5250 2225)(-5250 2175);
WIRE 16 -1 (-5250 2225)(-5500 2225);
WIRE 16 -1 (-5250 2175)(-5250 2125);
WIRE 16 -1 (-5250 2175)(-5500 2175);
WIRE 16 -1 (-5250 2125)(-5250 2075);
WIRE 16 -1 (-5250 2125)(-5500 2125);
WIRE 16 -1 (-5250 2075)(-5250 2025);
WIRE 16 -1 (-5250 2075)(-5500 2075);
WIRE 16 -1 (-5250 2025)(-5250 1975);
WIRE 16 -1 (-5250 2025)(-5500 2025);
WIRE 16 -1 (-5250 1975)(-5250 1925);
WIRE 16 -1 (-5250 1975)(-5500 1975);
WIRE 16 -1 (-5250 1925)(-5250 1875);
WIRE 16 -1 (-5250 1925)(-5500 1925);
WIRE 16 -1 (-5250 1875)(-5250 1825);
WIRE 16 -1 (-5250 1875)(-5500 1875);
WIRE 16 -1 (-5250 1825)(-5250 1775);
WIRE 16 -1 (-5250 1825)(-5500 1825);
WIRE 16 -1 (-5250 1775)(-5250 1725);
WIRE 16 -1 (-5250 1775)(-5500 1775);
WIRE 16 -1 (-5250 1725)(-5250 1675);
WIRE 16 -1 (-5250 1725)(-5500 1725);
WIRE 16 -1 (-5250 1675)(-5250 1625);
WIRE 16 -1 (-5250 1675)(-5500 1675);
WIRE 16 -1 (-5250 1625)(-5250 1575);
WIRE 16 -1 (-5250 1625)(-5500 1625);
WIRE 16 -1 (-5250 1575)(-5250 1525);
WIRE 16 -1 (-5250 1575)(-5500 1575);
WIRE 16 -1 (-5250 1525)(-5250 1475);
WIRE 16 -1 (-5250 1525)(-5500 1525);
WIRE 16 -1 (-5250 1475)(-5250 1425);
WIRE 16 -1 (-5250 1475)(-5500 1475);
WIRE 16 -1 (-5250 1425)(-5250 1375);
WIRE 16 -1 (-5250 1425)(-5500 1425);
WIRE 16 -1 (-5250 1375)(-5250 1325);
WIRE 16 -1 (-5250 1375)(-5500 1375);
WIRE 16 -1 (-5250 1325)(-5250 1275);
WIRE 16 -1 (-5250 1325)(-5500 1325);
WIRE 16 -1 (-5250 1275)(-5250 1225);
WIRE 16 -1 (-5250 1275)(-5500 1275);
WIRE 16 -1 (-5250 1225)(-5250 1175);
WIRE 16 -1 (-5250 1225)(-5500 1225);
WIRE 16 -1 (-5250 1175)(-5250 1125);
WIRE 16 -1 (-5250 1175)(-5500 1175);
WIRE 16 -1 (-5250 1125)(-5250 1075);
WIRE 16 -1 (-5250 1125)(-5500 1125);
WIRE 16 -1 (-5250 1075)(-5250 1025);
WIRE 16 -1 (-5250 1075)(-5500 1075);
WIRE 16 -1 (-5250 1025)(-5250 975);
WIRE 16 -1 (-5250 1025)(-5500 1025);
WIRE 16 -1 (-5250 975)(-5250 925);
WIRE 16 -1 (-5250 975)(-5500 975);
WIRE 16 -1 (-5250 925)(-5250 875);
WIRE 16 -1 (-5250 925)(-5500 925);
WIRE 16 -1 (-5250 875)(-5250 825);
WIRE 16 -1 (-5250 875)(-5500 875);
WIRE 16 -1 (-5250 825)(-5250 775);
WIRE 16 -1 (-5250 825)(-5500 825);
WIRE 16 -1 (-5250 775)(-5500 775);
WIRE 16 -1 (-3375 4300)(-3375 4175);
WIRE 16 -1 (-3375 4175)(-3375 4125);
WIRE 16 -1 (-3375 4175)(-3125 4175);
WIRE 16 -1 (-3375 4125)(-3375 4075);
WIRE 16 -1 (-3375 4125)(-3125 4125);
WIRE 16 -1 (-3375 4075)(-3375 4025);
WIRE 16 -1 (-3375 4075)(-3125 4075);
WIRE 16 -1 (-3375 4025)(-3375 3975);
WIRE 16 -1 (-3375 4025)(-3125 4025);
WIRE 16 -1 (-3375 3975)(-3375 3925);
WIRE 16 -1 (-3375 3975)(-3125 3975);
WIRE 16 -1 (-3375 3925)(-3375 3875);
WIRE 16 -1 (-3375 3925)(-3125 3925);
WIRE 16 -1 (-3375 3875)(-3375 3825);
WIRE 16 -1 (-3375 3875)(-3125 3875);
WIRE 16 -1 (-3375 3825)(-3375 3775);
WIRE 16 -1 (-3375 3825)(-3125 3825);
WIRE 16 -1 (-3375 3775)(-3375 3725);
WIRE 16 -1 (-3375 3775)(-3125 3775);
WIRE 16 -1 (-3375 3725)(-3375 3675);
WIRE 16 -1 (-3375 3725)(-3125 3725);
WIRE 16 -1 (-3375 3675)(-3375 3625);
WIRE 16 -1 (-3375 3675)(-3125 3675);
WIRE 16 -1 (-3375 3625)(-3375 3575);
WIRE 16 -1 (-3375 3625)(-3125 3625);
WIRE 16 -1 (-3375 3575)(-3375 3525);
WIRE 16 -1 (-3375 3575)(-3125 3575);
WIRE 16 -1 (-3375 3525)(-3375 3475);
WIRE 16 -1 (-3375 3525)(-3125 3525);
WIRE 16 -1 (-3375 3475)(-3375 3425);
WIRE 16 -1 (-3375 3475)(-3125 3475);
WIRE 16 -1 (-3375 3425)(-3375 3375);
WIRE 16 -1 (-3375 3425)(-3125 3425);
WIRE 16 -1 (-3375 3375)(-3375 3325);
WIRE 16 -1 (-3375 3375)(-3125 3375);
WIRE 16 -1 (-3375 3325)(-3375 3275);
WIRE 16 -1 (-3375 3325)(-3125 3325);
WIRE 16 -1 (-3375 3275)(-3375 3225);
WIRE 16 -1 (-3375 3275)(-3125 3275);
WIRE 16 -1 (-3375 3225)(-3375 3175);
WIRE 16 -1 (-3375 3225)(-3125 3225);
WIRE 16 -1 (-3375 3175)(-3375 3125);
WIRE 16 -1 (-3375 3175)(-3125 3175);
WIRE 16 -1 (-3375 3125)(-3375 3075);
WIRE 16 -1 (-3375 3125)(-3125 3125);
WIRE 16 -1 (-3375 3075)(-3375 3025);
WIRE 16 -1 (-3375 3075)(-3125 3075);
WIRE 16 -1 (-3375 3025)(-3375 2975);
WIRE 16 -1 (-3375 3025)(-3125 3025);
WIRE 16 -1 (-3375 2975)(-3375 2925);
WIRE 16 -1 (-3375 2975)(-3125 2975);
WIRE 16 -1 (-3375 2925)(-3375 2875);
WIRE 16 -1 (-3375 2925)(-3125 2925);
WIRE 16 -1 (-3375 2875)(-3375 2825);
WIRE 16 -1 (-3375 2875)(-3125 2875);
WIRE 16 -1 (-3375 2825)(-3375 2775);
WIRE 16 -1 (-3375 2825)(-3125 2825);
WIRE 16 -1 (-3375 2775)(-3375 2725);
WIRE 16 -1 (-3375 2775)(-3125 2775);
WIRE 16 -1 (-3375 2725)(-3375 2675);
WIRE 16 -1 (-3375 2725)(-3125 2725);
WIRE 16 -1 (-3375 2675)(-3375 2625);
WIRE 16 -1 (-3375 2675)(-3125 2675);
WIRE 16 -1 (-3375 2625)(-3375 2575);
WIRE 16 -1 (-3375 2625)(-3125 2625);
WIRE 16 -1 (-3375 2575)(-3375 2525);
WIRE 16 -1 (-3375 2575)(-3125 2575);
WIRE 16 -1 (-3375 2525)(-3375 2475);
WIRE 16 -1 (-3375 2525)(-3125 2525);
WIRE 16 -1 (-3375 2475)(-3375 2425);
WIRE 16 -1 (-3375 2475)(-3125 2475);
WIRE 16 -1 (-3375 2425)(-3375 2375);
WIRE 16 -1 (-3375 2425)(-3125 2425);
WIRE 16 -1 (-3375 2375)(-3375 2325);
WIRE 16 -1 (-3375 2375)(-3125 2375);
WIRE 16 -1 (-3375 2325)(-3375 2275);
WIRE 16 -1 (-3375 2325)(-3125 2325);
WIRE 16 -1 (-3375 2275)(-3375 2225);
WIRE 16 -1 (-3375 2275)(-3125 2275);
WIRE 16 -1 (-3375 2225)(-3375 2175);
WIRE 16 -1 (-3375 2225)(-3125 2225);
WIRE 16 -1 (-3375 2175)(-3375 2125);
WIRE 16 -1 (-3375 2175)(-3125 2175);
WIRE 16 -1 (-3375 2125)(-3375 2075);
WIRE 16 -1 (-3375 2125)(-3125 2125);
WIRE 16 -1 (-3375 2075)(-3375 2025);
WIRE 16 -1 (-3375 2075)(-3125 2075);
WIRE 16 -1 (-3375 2025)(-3375 1975);
WIRE 16 -1 (-3375 2025)(-3125 2025);
WIRE 16 -1 (-3375 1975)(-3375 1925);
WIRE 16 -1 (-3375 1975)(-3125 1975);
WIRE 16 -1 (-3375 1925)(-3375 1875);
WIRE 16 -1 (-3375 1925)(-3125 1925);
WIRE 16 -1 (-3375 1875)(-3375 1825);
WIRE 16 -1 (-3375 1875)(-3125 1875);
WIRE 16 -1 (-3375 1825)(-3375 1775);
WIRE 16 -1 (-3375 1825)(-3125 1825);
WIRE 16 -1 (-3375 1775)(-3375 1725);
WIRE 16 -1 (-3375 1775)(-3125 1775);
WIRE 16 -1 (-3375 1725)(-3375 1675);
WIRE 16 -1 (-3375 1725)(-3125 1725);
WIRE 16 -1 (-3375 1675)(-3375 1625);
WIRE 16 -1 (-3375 1675)(-3125 1675);
WIRE 16 -1 (-3375 1625)(-3375 1575);
WIRE 16 -1 (-3375 1625)(-3125 1625);
WIRE 16 -1 (-3375 1575)(-3375 1525);
WIRE 16 -1 (-3375 1575)(-3125 1575);
WIRE 16 -1 (-3375 1525)(-3375 1475);
WIRE 16 -1 (-3375 1525)(-3125 1525);
WIRE 16 -1 (-3375 1475)(-3375 1425);
WIRE 16 -1 (-3375 1475)(-3125 1475);
WIRE 16 -1 (-3375 1425)(-3375 1375);
WIRE 16 -1 (-3375 1425)(-3125 1425);
WIRE 16 -1 (-3375 1375)(-3375 1325);
WIRE 16 -1 (-3375 1375)(-3125 1375);
WIRE 16 -1 (-3375 1325)(-3375 1275);
WIRE 16 -1 (-3375 1325)(-3125 1325);
WIRE 16 -1 (-3375 1275)(-3375 1225);
WIRE 16 -1 (-3375 1275)(-3125 1275);
WIRE 16 -1 (-3375 1225)(-3375 1175);
WIRE 16 -1 (-3375 1225)(-3125 1225);
WIRE 16 -1 (-3375 1175)(-3375 1125);
WIRE 16 -1 (-3375 1175)(-3125 1175);
WIRE 16 -1 (-3375 1125)(-3375 1075);
WIRE 16 -1 (-3375 1125)(-3125 1125);
WIRE 16 -1 (-3375 1075)(-3375 1025);
WIRE 16 -1 (-3375 1075)(-3125 1075);
WIRE 16 -1 (-3375 1025)(-3375 975);
WIRE 16 -1 (-3375 1025)(-3125 1025);
WIRE 16 -1 (-3375 975)(-3375 925);
WIRE 16 -1 (-3375 975)(-3125 975);
WIRE 16 -1 (-3375 925)(-3375 875);
WIRE 16 -1 (-3375 925)(-3125 925);
WIRE 16 -1 (-3375 875)(-3375 825);
WIRE 16 -1 (-3375 875)(-3125 875);
WIRE 16 -1 (-3375 825)(-3375 775);
WIRE 16 -1 (-3375 825)(-3125 825);
WIRE 16 -1 (-3375 775)(-3125 775);
WIRE 16 -1 (-1500 4275)(-1500 4175);
WIRE 16 -1 (-1500 4175)(-1500 4125);
WIRE 16 -1 (-1500 4175)(-1725 4175);
WIRE 16 -1 (-1500 4125)(-1500 4075);
WIRE 16 -1 (-1500 4125)(-1725 4125);
WIRE 16 -1 (-1500 4075)(-1500 4025);
WIRE 16 -1 (-1500 4075)(-1725 4075);
WIRE 16 -1 (-1500 4025)(-1500 3975);
WIRE 16 -1 (-1500 4025)(-1725 4025);
WIRE 16 -1 (-1500 3975)(-1500 3925);
WIRE 16 -1 (-1500 3975)(-1725 3975);
WIRE 16 -1 (-1500 3925)(-1500 3875);
WIRE 16 -1 (-1500 3925)(-1725 3925);
WIRE 16 -1 (-1500 3875)(-1500 3825);
WIRE 16 -1 (-1500 3875)(-1725 3875);
WIRE 16 -1 (-1500 3825)(-1500 3775);
WIRE 16 -1 (-1500 3825)(-1725 3825);
WIRE 16 -1 (-1500 3775)(-1500 3725);
WIRE 16 -1 (-1500 3775)(-1725 3775);
WIRE 16 -1 (-1500 3725)(-1500 3675);
WIRE 16 -1 (-1500 3725)(-1725 3725);
WIRE 16 -1 (-1500 3675)(-1500 3625);
WIRE 16 -1 (-1500 3675)(-1725 3675);
WIRE 16 -1 (-1500 3625)(-1500 3575);
WIRE 16 -1 (-1500 3625)(-1725 3625);
WIRE 16 -1 (-1500 3575)(-1500 3525);
WIRE 16 -1 (-1500 3575)(-1725 3575);
WIRE 16 -1 (-1500 3525)(-1500 3475);
WIRE 16 -1 (-1500 3525)(-1725 3525);
WIRE 16 -1 (-1500 3475)(-1500 3425);
WIRE 16 -1 (-1500 3475)(-1725 3475);
WIRE 16 -1 (-1500 3425)(-1500 3375);
WIRE 16 -1 (-1500 3425)(-1725 3425);
WIRE 16 -1 (-1500 3375)(-1500 3325);
WIRE 16 -1 (-1500 3375)(-1725 3375);
WIRE 16 -1 (-1500 3325)(-1500 3275);
WIRE 16 -1 (-1500 3325)(-1725 3325);
WIRE 16 -1 (-1500 3275)(-1500 3225);
WIRE 16 -1 (-1500 3275)(-1725 3275);
WIRE 16 -1 (-1500 3225)(-1500 3175);
WIRE 16 -1 (-1500 3225)(-1725 3225);
WIRE 16 -1 (-1500 3175)(-1500 3125);
WIRE 16 -1 (-1500 3175)(-1725 3175);
WIRE 16 -1 (-1500 3125)(-1500 3075);
WIRE 16 -1 (-1500 3125)(-1725 3125);
WIRE 16 -1 (-1500 3075)(-1500 3025);
WIRE 16 -1 (-1500 3075)(-1725 3075);
WIRE 16 -1 (-1500 3025)(-1500 2975);
WIRE 16 -1 (-1500 3025)(-1725 3025);
WIRE 16 -1 (-1500 2975)(-1500 2925);
WIRE 16 -1 (-1500 2975)(-1725 2975);
WIRE 16 -1 (-1500 2925)(-1500 2875);
WIRE 16 -1 (-1500 2925)(-1725 2925);
WIRE 16 -1 (-1500 2875)(-1500 2825);
WIRE 16 -1 (-1500 2875)(-1725 2875);
WIRE 16 -1 (-1500 2825)(-1500 2775);
WIRE 16 -1 (-1500 2825)(-1725 2825);
WIRE 16 -1 (-1500 2775)(-1500 2725);
WIRE 16 -1 (-1500 2775)(-1725 2775);
WIRE 16 -1 (-1500 2725)(-1500 2675);
WIRE 16 -1 (-1500 2725)(-1725 2725);
WIRE 16 -1 (-1500 2675)(-1500 2625);
WIRE 16 -1 (-1500 2675)(-1725 2675);
WIRE 16 -1 (-1500 2625)(-1500 2575);
WIRE 16 -1 (-1500 2625)(-1725 2625);
WIRE 16 -1 (-1500 2575)(-1500 2525);
WIRE 16 -1 (-1500 2575)(-1725 2575);
WIRE 16 -1 (-1500 2525)(-1500 2475);
WIRE 16 -1 (-1500 2525)(-1725 2525);
WIRE 16 -1 (-1500 2475)(-1500 2425);
WIRE 16 -1 (-1500 2475)(-1725 2475);
WIRE 16 -1 (-1500 2425)(-1500 2375);
WIRE 16 -1 (-1500 2425)(-1725 2425);
WIRE 16 -1 (-1500 2375)(-1500 2325);
WIRE 16 -1 (-1500 2375)(-1725 2375);
WIRE 16 -1 (-1500 2325)(-1500 2275);
WIRE 16 -1 (-1500 2325)(-1725 2325);
WIRE 16 -1 (-1500 2275)(-1500 2225);
WIRE 16 -1 (-1500 2275)(-1725 2275);
WIRE 16 -1 (-1500 2225)(-1500 2175);
WIRE 16 -1 (-1500 2225)(-1725 2225);
WIRE 16 -1 (-1500 2175)(-1500 2125);
WIRE 16 -1 (-1500 2175)(-1725 2175);
WIRE 16 -1 (-1500 2125)(-1500 2075);
WIRE 16 -1 (-1500 2125)(-1725 2125);
WIRE 16 -1 (-1500 2075)(-1500 2025);
WIRE 16 -1 (-1500 2075)(-1725 2075);
WIRE 16 -1 (-1500 2025)(-1500 1975);
WIRE 16 -1 (-1500 2025)(-1725 2025);
WIRE 16 -1 (-1500 1975)(-1500 1925);
WIRE 16 -1 (-1500 1975)(-1725 1975);
WIRE 16 -1 (-1500 1925)(-1500 1875);
WIRE 16 -1 (-1500 1925)(-1725 1925);
WIRE 16 -1 (-1500 1875)(-1500 1825);
WIRE 16 -1 (-1500 1875)(-1725 1875);
WIRE 16 -1 (-1500 1825)(-1500 1775);
WIRE 16 -1 (-1500 1825)(-1725 1825);
WIRE 16 -1 (-1500 1775)(-1500 1725);
WIRE 16 -1 (-1500 1775)(-1725 1775);
WIRE 16 -1 (-1500 1725)(-1500 1675);
WIRE 16 -1 (-1500 1725)(-1725 1725);
WIRE 16 -1 (-1500 1675)(-1500 1625);
WIRE 16 -1 (-1500 1675)(-1725 1675);
WIRE 16 -1 (-1500 1625)(-1500 1575);
WIRE 16 -1 (-1500 1625)(-1725 1625);
WIRE 16 -1 (-1500 1575)(-1500 1525);
WIRE 16 -1 (-1500 1575)(-1725 1575);
WIRE 16 -1 (-1500 1525)(-1500 1475);
WIRE 16 -1 (-1500 1525)(-1725 1525);
WIRE 16 -1 (-1500 1475)(-1500 1425);
WIRE 16 -1 (-1500 1475)(-1725 1475);
WIRE 16 -1 (-1500 1425)(-1500 1375);
WIRE 16 -1 (-1500 1425)(-1725 1425);
WIRE 16 -1 (-1500 1375)(-1500 1325);
WIRE 16 -1 (-1500 1375)(-1725 1375);
WIRE 16 -1 (-1500 1325)(-1500 1275);
WIRE 16 -1 (-1500 1325)(-1725 1325);
WIRE 16 -1 (-1500 1275)(-1500 1225);
WIRE 16 -1 (-1500 1275)(-1725 1275);
WIRE 16 -1 (-1500 1225)(-1500 1175);
WIRE 16 -1 (-1500 1225)(-1725 1225);
WIRE 16 -1 (-1500 1175)(-1725 1175);
WIRE 16 -1 (-375 650)(-375 575);
WIRE 16 -1 (-775 1450)(-775 1575);
WIRE 16 -1 (-375 1225)(-375 1400);
WIRE 16 -1 (-800 775)(-1725 775);
FORCEPROP 0 LAST SIG_NAME VSENSE_PVCCIN_CPU0_SKT_VSEN
J 0
(-1550 784);
DISPLAY 0.617021 (-1550 784);
PAINT ORANGE (-1550 784);
WIRE 16 -1 (-800 725)(-1725 725);
FORCEPROP 0 LAST SIG_NAME VSENSE_PVCCIN_CPU0_SKT_VRTN
J 0
(-1550 725);
DISPLAY 0.617021 (-1550 725);
PAINT ORANGE (-1550 725);
WIRE 16 -1 (-775 975)(-1725 975);
WIRE 16 -1 (-775 1075)(-1725 1075);
FORCEPROP 0 LAST SIG_NAME VSENSE_VCCINR2PMAX_CPU0
J 0
(-1550 1085);
DISPLAY 0.617021 (-1550 1085);
PAINT ORANGE (-1550 1085);
FORCEPROP 2 LASTPROP $XRERR UNIQUE?
J 0
(-1790 1085);
DISPLAY 0.638298 (-1790 1085);
PAINT MONO (-1790 1085);
DISPLAY INVISIBLE (-1790 1085);
WIRE 16 -1 (-775 1075)(-775 975);
WIRE 16 -1 (-775 1075)(-775 1250);
WIRE 16 -1 (-375 875)(-1725 875);
FORCEPROP 0 LAST SIG_NAME VSENSE_PMAX_CPU0
J 0
(-1550 885);
DISPLAY 0.617021 (-1550 885);
PAINT ORANGE (-1550 885);
FORCEPROP 2 LASTPROP $XRERR UNIQUE?
J 0
(-1790 885);
DISPLAY 0.638298 (-1790 885);
PAINT MONO (-1790 885);
DISPLAY INVISIBLE (-1790 885);
WIRE 16 -1 (-375 850)(-375 875);
WIRE 16 -1 (-375 875)(-375 1025);
DOT 1 (-7125 825);
DOT 1 (-7125 875);
DOT 1 (-7125 925);
DOT 1 (-7125 975);
DOT 1 (-7125 1025);
DOT 1 (-7125 1075);
DOT 1 (-7125 1125);
DOT 1 (-7125 1175);
DOT 1 (-7125 1225);
DOT 1 (-7125 1275);
DOT 1 (-7125 1325);
DOT 1 (-7125 1375);
DOT 1 (-7125 1425);
DOT 1 (-7125 1475);
DOT 1 (-7125 1525);
DOT 1 (-7125 1625);
DOT 1 (-7125 1575);
DOT 1 (-7125 1675);
DOT 1 (-7125 1725);
DOT 1 (-7125 1775);
DOT 1 (-7125 1825);
DOT 1 (-7125 1875);
DOT 1 (-7125 1925);
DOT 1 (-7125 1975);
DOT 1 (-7125 2025);
DOT 1 (-7125 2075);
DOT 1 (-7125 2125);
DOT 1 (-7125 2175);
DOT 1 (-7125 2275);
DOT 1 (-7125 2225);
DOT 1 (-7125 2325);
DOT 1 (-7125 2375);
DOT 1 (-7125 2425);
DOT 1 (-7125 2525);
DOT 1 (-7125 2475);
DOT 1 (-7125 2575);
DOT 1 (-7125 2625);
DOT 1 (-7125 2725);
DOT 1 (-7125 2775);
DOT 1 (-7125 2825);
DOT 1 (-7125 2875);
DOT 1 (-7125 2925);
DOT 1 (-7125 2975);
DOT 1 (-7125 3025);
DOT 1 (-7125 3075);
DOT 1 (-7125 3125);
DOT 1 (-7125 3175);
DOT 1 (-7125 3225);
DOT 1 (-7125 3275);
DOT 1 (-7125 3325);
DOT 1 (-7125 3375);
DOT 1 (-7125 3425);
DOT 1 (-7125 3475);
DOT 1 (-7125 3525);
DOT 1 (-7125 3575);
DOT 1 (-7125 3675);
DOT 1 (-7125 3625);
DOT 1 (-7125 3725);
DOT 1 (-7125 3775);
DOT 1 (-7125 3825);
DOT 1 (-7125 3875);
DOT 1 (-7125 3925);
DOT 1 (-7125 3975);
DOT 1 (-7125 4025);
DOT 1 (-7125 4075);
DOT 1 (-5250 825);
DOT 1 (-5250 875);
DOT 1 (-5250 975);
DOT 1 (-5250 925);
DOT 1 (-5250 1025);
DOT 1 (-5250 1125);
DOT 1 (-5250 1075);
DOT 1 (-5250 1175);
DOT 1 (-5250 1225);
DOT 1 (-5250 1275);
DOT 1 (-5250 1325);
DOT 1 (-5250 1375);
DOT 1 (-5250 1475);
DOT 1 (-5250 1525);
DOT 1 (-5250 1425);
DOT 1 (-5250 1625);
DOT 1 (-5250 1575);
DOT 1 (-5250 1675);
DOT 1 (-5250 1725);
DOT 1 (-5250 1775);
DOT 1 (-5250 1825);
DOT 1 (-5250 1875);
DOT 1 (-5250 1925);
DOT 1 (-5250 2025);
DOT 1 (-5250 1975);
DOT 1 (-5250 2125);
DOT 1 (-5250 2075);
DOT 1 (-5250 2175);
DOT 1 (-5250 2275);
DOT 1 (-5250 2225);
DOT 1 (-5250 2425);
DOT 1 (-5250 2375);
DOT 1 (-5250 2325);
DOT 1 (-5250 2475);
DOT 1 (-5250 2525);
DOT 1 (-5250 2625);
DOT 1 (-5250 2575);
DOT 1 (-5250 2675);
DOT 1 (-5250 2775);
DOT 1 (-5250 2725);
DOT 1 (-5250 2825);
DOT 1 (-5250 2925);
DOT 1 (-5250 2875);
DOT 1 (-5250 3025);
DOT 1 (-5250 2975);
DOT 1 (-5250 3075);
DOT 1 (-5250 3175);
DOT 1 (-5250 3225);
DOT 1 (-5250 3325);
DOT 1 (-5250 3275);
DOT 1 (-5250 3375);
DOT 1 (-5250 3425);
DOT 1 (-5250 3525);
DOT 1 (-5250 3575);
DOT 1 (-5250 3475);
DOT 1 (-5250 3625);
DOT 1 (-5250 3675);
DOT 1 (-5250 3725);
DOT 1 (-5250 3775);
DOT 1 (-5250 3825);
DOT 1 (-5250 3875);
DOT 1 (-5250 3925);
DOT 1 (-5250 3975);
DOT 1 (-5250 4075);
DOT 1 (-5250 4025);
DOT 1 (-7125 4175);
DOT 1 (-7125 4125);
DOT 1 (-5250 4175);
DOT 1 (-5250 4125);
DOT 1 (-3375 825);
DOT 1 (-3375 875);
DOT 1 (-3375 975);
DOT 1 (-3375 925);
DOT 1 (-3375 1025);
DOT 1 (-3375 1075);
DOT 1 (-3375 1125);
DOT 1 (-3375 1175);
DOT 1 (-3375 1225);
DOT 1 (-3375 1275);
DOT 1 (-3375 1375);
DOT 1 (-3375 1325);
DOT 1 (-3375 1425);
DOT 1 (-3375 1475);
DOT 1 (-3375 1525);
DOT 1 (-3375 1625);
DOT 1 (-3375 1575);
DOT 1 (-3375 1675);
DOT 1 (-3375 1725);
DOT 1 (-3375 1775);
DOT 1 (-3375 1875);
DOT 1 (-3375 1825);
DOT 1 (-3375 1925);
DOT 1 (-3375 1975);
DOT 1 (-3375 2025);
DOT 1 (-3375 2075);
DOT 1 (-3375 2125);
DOT 1 (-3375 2175);
DOT 1 (-3375 2275);
DOT 1 (-3375 2225);
DOT 1 (-3375 2325);
DOT 1 (-3375 2375);
DOT 1 (-3375 2425);
DOT 1 (-3375 2475);
DOT 1 (-3375 2525);
DOT 1 (-3375 2575);
DOT 1 (-3375 2625);
DOT 1 (-3375 2675);
DOT 1 (-3375 2775);
DOT 1 (-3375 2725);
DOT 1 (-3375 2825);
DOT 1 (-3375 2875);
DOT 1 (-3375 2925);
DOT 1 (-3375 2975);
DOT 1 (-3375 3025);
DOT 1 (-3375 3075);
DOT 1 (-3375 3125);
DOT 1 (-3375 3175);
DOT 1 (-3375 3225);
DOT 1 (-3375 3275);
DOT 1 (-3375 3325);
DOT 1 (-3375 3425);
DOT 1 (-3375 3375);
DOT 1 (-3375 3475);
DOT 1 (-3375 3525);
DOT 1 (-3375 3575);
DOT 1 (-3375 3625);
DOT 1 (-3375 3675);
DOT 1 (-3375 3725);
DOT 1 (-3375 3775);
DOT 1 (-3375 3825);
DOT 1 (-3375 3875);
DOT 1 (-3375 3925);
DOT 1 (-3375 3975);
DOT 1 (-3375 4025);
DOT 1 (-3375 4075);
DOT 1 (-1500 1275);
DOT 1 (-1500 1225);
DOT 1 (-1500 1325);
DOT 1 (-1500 1375);
DOT 1 (-1500 1425);
DOT 1 (-1500 1475);
DOT 1 (-1500 1525);
DOT 1 (-1500 1575);
DOT 1 (-1500 1625);
DOT 1 (-1500 1675);
DOT 1 (-1500 1725);
DOT 1 (-1500 1775);
DOT 1 (-1500 1825);
DOT 1 (-1500 1875);
DOT 1 (-1500 1925);
DOT 1 (-1500 1975);
DOT 1 (-1500 2025);
DOT 1 (-375 875);
DOT 1 (-775 1075);
DOT 1 (-1500 2075);
DOT 1 (-1500 2125);
DOT 1 (-1500 2175);
DOT 1 (-1500 2275);
DOT 1 (-1500 2225);
DOT 1 (-1500 2325);
DOT 1 (-1500 2375);
DOT 1 (-1500 2425);
DOT 1 (-1500 2475);
DOT 1 (-1500 2525);
DOT 1 (-1500 2575);
DOT 1 (-1500 2625);
DOT 1 (-1500 2675);
DOT 1 (-1500 2775);
DOT 1 (-1500 2725);
DOT 1 (-1500 2825);
DOT 1 (-1500 2875);
DOT 1 (-1500 2925);
DOT 1 (-1500 3025);
DOT 1 (-1500 2975);
DOT 1 (-1500 3075);
DOT 1 (-1500 3125);
DOT 1 (-1500 3175);
DOT 1 (-1500 3225);
DOT 1 (-1500 3325);
DOT 1 (-1500 3425);
DOT 1 (-1500 3375);
DOT 1 (-1500 3475);
DOT 1 (-1500 3525);
DOT 1 (-1500 3575);
DOT 1 (-1500 3675);
DOT 1 (-1500 3625);
DOT 1 (-1500 3725);
DOT 1 (-1500 3775);
DOT 1 (-1500 3825);
DOT 1 (-1500 3925);
DOT 1 (-1500 3875);
DOT 1 (-1500 3975);
DOT 1 (-1500 4025);
DOT 1 (-1500 4075);
DOT 1 (-3375 4125);
DOT 1 (-3375 4175);
DOT 1 (-1500 4125);
DOT 1 (-1500 4175);
DOT 1 (-5250 3125);
DOT 1 (-1500 3275);
DOT 1 (-7125 2675);
FORCENOTE
SKYLAKE - SKT0 - 17 OF 21
(-1625 125) 0;
DISPLAY LEFT (-1625 125);
DISPLAY 1.021277 (-1625 125);
PAINT RED (-1625 125);
FORCENOTE
ROOM=CPU0
(-7925 325) 0;
DISPLAY LEFT (-7925 325);
DISPLAY 1.382979 (-7925 325);
PAINT PURPLE (-7925 325);
FORCENOTE
BOM_COST=PROC_SOCKET
(-7925 225) 0;
DISPLAY LEFT (-7925 225);
DISPLAY 1.382979 (-7925 225);
PAINT PURPLE (-7925 225);
QUIT
